G04*
G04 #@! TF.GenerationSoftware,Altium Limited,Altium Designer,22.4.2 (48)*
G04*
G04 Layer_Color=128*
%FSLAX25Y25*%
%MOIN*%
G70*
G04*
G04 #@! TF.SameCoordinates,446674BB-F454-490D-8607-5140536C8ADF*
G04*
G04*
G04 #@! TF.FilePolarity,Positive*
G04*
G01*
G75*
%ADD72R,0.02800X0.16500*%
%ADD73R,0.02800X0.12600*%
%ADD173R,0.02520X0.02677*%
G36*
X315016Y-7748D02*
X315610D01*
Y-7802D01*
X315827D01*
Y-7856D01*
X316043D01*
Y-7910D01*
X316205D01*
Y-7964D01*
X316313D01*
Y-8018D01*
X316475D01*
Y-8072D01*
X316583D01*
Y-8126D01*
X316691D01*
Y-8180D01*
X316800D01*
Y-8234D01*
X316854D01*
Y-8288D01*
X316962D01*
Y-8342D01*
X317016D01*
Y-8396D01*
X317124D01*
Y-8450D01*
X317178D01*
Y-8504D01*
X317232D01*
Y-8558D01*
X317286D01*
Y-8613D01*
X317340D01*
Y-8667D01*
X317394D01*
Y-8721D01*
X317448D01*
Y-8775D01*
X317502D01*
Y-8829D01*
X317557D01*
Y-8883D01*
X317611D01*
Y-8937D01*
X317665D01*
Y-8991D01*
X317719D01*
Y-9045D01*
X317773D01*
Y-9099D01*
X317827D01*
Y-9153D01*
Y-9207D01*
X317881D01*
Y-9261D01*
X317935D01*
Y-9315D01*
Y-9369D01*
X317989D01*
Y-9424D01*
X318043D01*
Y-9478D01*
Y-9532D01*
X318097D01*
Y-9586D01*
Y-9640D01*
X318151D01*
Y-9694D01*
Y-9748D01*
X318205D01*
Y-9802D01*
Y-9856D01*
X318259D01*
Y-9910D01*
Y-9964D01*
Y-10018D01*
X318313D01*
Y-10072D01*
Y-10126D01*
X318367D01*
Y-10180D01*
Y-10234D01*
Y-10289D01*
Y-10343D01*
X318422D01*
Y-10397D01*
Y-10451D01*
Y-10505D01*
Y-10559D01*
X318476D01*
Y-10613D01*
Y-10667D01*
Y-10721D01*
Y-10775D01*
Y-10829D01*
Y-10883D01*
Y-10937D01*
X318530D01*
Y-10991D01*
Y-11045D01*
Y-11099D01*
Y-11153D01*
Y-11208D01*
Y-11262D01*
Y-11316D01*
Y-11370D01*
Y-11424D01*
Y-11478D01*
Y-11532D01*
Y-11586D01*
Y-11640D01*
X318476D01*
Y-11694D01*
Y-11748D01*
Y-11802D01*
Y-11856D01*
Y-11910D01*
X318422D01*
Y-11964D01*
Y-12019D01*
Y-12072D01*
Y-12127D01*
Y-12181D01*
X318367D01*
Y-12235D01*
Y-12289D01*
Y-12343D01*
X318313D01*
Y-12397D01*
Y-12451D01*
Y-12505D01*
X318259D01*
Y-12559D01*
Y-12613D01*
Y-12667D01*
X318205D01*
Y-12721D01*
Y-12775D01*
X318151D01*
Y-12829D01*
Y-12883D01*
X318097D01*
Y-12937D01*
Y-12992D01*
X318043D01*
Y-13046D01*
X317989D01*
Y-13100D01*
Y-13154D01*
X317935D01*
Y-13208D01*
Y-13262D01*
X317881D01*
Y-13316D01*
X317827D01*
Y-13370D01*
X317773D01*
Y-13424D01*
Y-13478D01*
X317719D01*
Y-13532D01*
X317665D01*
Y-13586D01*
X317611D01*
Y-13640D01*
X317557D01*
Y-13694D01*
X317502D01*
Y-13748D01*
X317448D01*
Y-13803D01*
X317394D01*
Y-13857D01*
X317340D01*
Y-13911D01*
X317286D01*
Y-13965D01*
X317232D01*
Y-14019D01*
X317178D01*
Y-14073D01*
X317070D01*
Y-14127D01*
X317016D01*
Y-14181D01*
X316908D01*
Y-14235D01*
X316854D01*
Y-14289D01*
X316746D01*
Y-14343D01*
X316637D01*
Y-14397D01*
X316583D01*
Y-14451D01*
X316421D01*
Y-14505D01*
X316313D01*
Y-14559D01*
X316151D01*
Y-14614D01*
X315989D01*
Y-14668D01*
X315827D01*
Y-14722D01*
X315556D01*
Y-14776D01*
X310312D01*
Y-14722D01*
X310042D01*
Y-14668D01*
X309826D01*
Y-14614D01*
X309664D01*
Y-14559D01*
X309501D01*
Y-14505D01*
X309393D01*
Y-14451D01*
X309285D01*
Y-14397D01*
X309177D01*
Y-14343D01*
X309069D01*
Y-14289D01*
X308961D01*
Y-14235D01*
X308907D01*
Y-14181D01*
X308799D01*
Y-14127D01*
X308744D01*
Y-14073D01*
X308690D01*
Y-14019D01*
X308636D01*
Y-13965D01*
X308528D01*
Y-13911D01*
X308474D01*
Y-13857D01*
X308420D01*
Y-13803D01*
X308366D01*
Y-13748D01*
X308312D01*
Y-13694D01*
X308258D01*
Y-13640D01*
X308204D01*
Y-13586D01*
X308150D01*
Y-13532D01*
X308096D01*
Y-13478D01*
Y-13424D01*
X308042D01*
Y-13370D01*
X307987D01*
Y-13316D01*
X307933D01*
Y-13262D01*
Y-13208D01*
X307879D01*
Y-13154D01*
X307825D01*
Y-13100D01*
Y-13046D01*
X307771D01*
Y-12992D01*
Y-12937D01*
X307717D01*
Y-12883D01*
Y-12829D01*
X307663D01*
Y-12775D01*
Y-12721D01*
X307609D01*
Y-12667D01*
Y-12613D01*
X307555D01*
Y-12559D01*
Y-12505D01*
Y-12451D01*
X307501D01*
Y-12397D01*
Y-12343D01*
Y-12289D01*
X307447D01*
Y-12235D01*
Y-12181D01*
Y-12127D01*
X307393D01*
Y-12072D01*
Y-12019D01*
Y-11964D01*
Y-11910D01*
Y-11856D01*
X307339D01*
Y-11802D01*
Y-11748D01*
Y-11694D01*
Y-11640D01*
Y-11586D01*
Y-11532D01*
Y-11478D01*
Y-11424D01*
Y-11370D01*
X307285D01*
Y-11316D01*
Y-11262D01*
Y-11208D01*
Y-11153D01*
X307339D01*
Y-11099D01*
Y-11045D01*
Y-10991D01*
Y-10937D01*
Y-10883D01*
Y-10829D01*
Y-10775D01*
Y-10721D01*
Y-10667D01*
Y-10613D01*
X307393D01*
Y-10559D01*
Y-10505D01*
Y-10451D01*
Y-10397D01*
X307447D01*
Y-10343D01*
Y-10289D01*
Y-10234D01*
Y-10180D01*
X307501D01*
Y-10126D01*
Y-10072D01*
Y-10018D01*
X307555D01*
Y-9964D01*
Y-9910D01*
X307609D01*
Y-9856D01*
Y-9802D01*
Y-9748D01*
X307663D01*
Y-9694D01*
Y-9640D01*
X307717D01*
Y-9586D01*
X307771D01*
Y-9532D01*
Y-9478D01*
X307825D01*
Y-9424D01*
Y-9369D01*
X307879D01*
Y-9315D01*
X307933D01*
Y-9261D01*
Y-9207D01*
X307987D01*
Y-9153D01*
X308042D01*
Y-9099D01*
Y-9045D01*
X308096D01*
Y-8991D01*
X308150D01*
Y-8937D01*
X308204D01*
Y-8883D01*
X308258D01*
Y-8829D01*
X308312D01*
Y-8775D01*
X308366D01*
Y-8721D01*
X308420D01*
Y-8667D01*
X308474D01*
Y-8613D01*
X308528D01*
Y-8558D01*
X308582D01*
Y-8504D01*
X308636D01*
Y-8450D01*
X308744D01*
Y-8396D01*
X308799D01*
Y-8342D01*
X308907D01*
Y-8288D01*
X308961D01*
Y-8234D01*
X309069D01*
Y-8180D01*
X309177D01*
Y-8126D01*
X309231D01*
Y-8072D01*
X309393D01*
Y-8018D01*
X309501D01*
Y-7964D01*
X309664D01*
Y-7910D01*
X309772D01*
Y-7856D01*
X309988D01*
Y-7802D01*
X310258D01*
Y-7748D01*
X310799D01*
Y-7694D01*
X310853D01*
Y-7748D01*
X310907D01*
Y-7694D01*
X315016D01*
Y-7748D01*
D02*
G37*
G36*
X395298D02*
X395352D01*
Y-7802D01*
Y-7856D01*
Y-7910D01*
Y-7964D01*
Y-8018D01*
Y-8072D01*
Y-8126D01*
Y-8180D01*
Y-8234D01*
Y-8288D01*
Y-8342D01*
Y-8396D01*
Y-8450D01*
Y-8504D01*
Y-8558D01*
Y-8613D01*
Y-8667D01*
Y-8721D01*
Y-8775D01*
Y-8829D01*
Y-8883D01*
Y-8937D01*
Y-8991D01*
Y-9045D01*
Y-9099D01*
Y-9153D01*
Y-9207D01*
Y-9261D01*
Y-9315D01*
Y-9369D01*
Y-9424D01*
Y-9478D01*
Y-9532D01*
Y-9586D01*
Y-9640D01*
Y-9694D01*
Y-9748D01*
Y-9802D01*
Y-9856D01*
Y-9910D01*
Y-9964D01*
Y-10018D01*
Y-10072D01*
Y-10126D01*
Y-10180D01*
Y-10234D01*
Y-10289D01*
Y-10343D01*
Y-10397D01*
Y-10451D01*
Y-10505D01*
Y-10559D01*
Y-10613D01*
Y-10667D01*
Y-10721D01*
Y-10775D01*
Y-10829D01*
Y-10883D01*
Y-10937D01*
Y-10991D01*
Y-11045D01*
Y-11099D01*
Y-11153D01*
Y-11208D01*
Y-11262D01*
Y-11316D01*
Y-11370D01*
Y-11424D01*
Y-11478D01*
Y-11532D01*
Y-11586D01*
Y-11640D01*
Y-11694D01*
Y-11748D01*
Y-11802D01*
Y-11856D01*
Y-11910D01*
Y-11964D01*
Y-12019D01*
Y-12072D01*
Y-12127D01*
Y-12181D01*
Y-12235D01*
Y-12289D01*
Y-12343D01*
Y-12397D01*
Y-12451D01*
Y-12505D01*
Y-12559D01*
Y-12613D01*
Y-12667D01*
Y-12721D01*
Y-12775D01*
Y-12829D01*
Y-12883D01*
Y-12937D01*
Y-12992D01*
Y-13046D01*
Y-13100D01*
Y-13154D01*
Y-13208D01*
Y-13262D01*
Y-13316D01*
Y-13370D01*
Y-13424D01*
Y-13478D01*
Y-13532D01*
Y-13586D01*
Y-13640D01*
Y-13694D01*
Y-13748D01*
Y-13803D01*
Y-13857D01*
Y-13911D01*
Y-13965D01*
Y-14019D01*
Y-14073D01*
Y-14127D01*
Y-14181D01*
Y-14235D01*
Y-14289D01*
Y-14343D01*
Y-14397D01*
Y-14451D01*
Y-14505D01*
Y-14559D01*
Y-14614D01*
Y-14668D01*
Y-14722D01*
Y-14776D01*
Y-14830D01*
Y-14884D01*
Y-14938D01*
Y-14992D01*
Y-15046D01*
Y-15100D01*
Y-15154D01*
Y-15208D01*
Y-15262D01*
Y-15316D01*
Y-15370D01*
Y-15424D01*
Y-15478D01*
Y-15532D01*
Y-15587D01*
Y-15641D01*
Y-15695D01*
Y-15749D01*
Y-15803D01*
Y-15857D01*
Y-15911D01*
Y-15965D01*
Y-16019D01*
Y-16073D01*
Y-16127D01*
Y-16181D01*
Y-16235D01*
Y-16289D01*
Y-16343D01*
Y-16398D01*
Y-16452D01*
Y-16506D01*
Y-16560D01*
Y-16614D01*
Y-16668D01*
Y-16722D01*
Y-16776D01*
Y-16830D01*
Y-16884D01*
Y-16938D01*
Y-16992D01*
Y-17046D01*
Y-17100D01*
Y-17154D01*
Y-17208D01*
Y-17263D01*
Y-17317D01*
Y-17371D01*
Y-17425D01*
Y-17479D01*
Y-17533D01*
Y-17587D01*
Y-17641D01*
Y-17695D01*
Y-17749D01*
Y-17803D01*
Y-17857D01*
Y-17911D01*
Y-17965D01*
Y-18019D01*
Y-18073D01*
Y-18127D01*
Y-18181D01*
Y-18236D01*
Y-18290D01*
Y-18344D01*
Y-18398D01*
Y-18452D01*
Y-18506D01*
Y-18560D01*
Y-18614D01*
Y-18668D01*
Y-18722D01*
Y-18776D01*
Y-18830D01*
Y-18884D01*
Y-18938D01*
Y-18993D01*
Y-19047D01*
Y-19101D01*
Y-19155D01*
Y-19209D01*
Y-19263D01*
Y-19317D01*
Y-19371D01*
Y-19425D01*
Y-19479D01*
Y-19533D01*
Y-19587D01*
Y-19641D01*
Y-19695D01*
Y-19749D01*
Y-19803D01*
Y-19858D01*
Y-19911D01*
Y-19966D01*
Y-20020D01*
Y-20074D01*
Y-20128D01*
Y-20182D01*
Y-20236D01*
Y-20290D01*
Y-20344D01*
Y-20398D01*
Y-20452D01*
Y-20506D01*
Y-20560D01*
Y-20614D01*
Y-20668D01*
Y-20722D01*
Y-20776D01*
Y-20831D01*
Y-20885D01*
Y-20939D01*
Y-20993D01*
Y-21047D01*
Y-21101D01*
Y-21155D01*
Y-21209D01*
Y-21263D01*
Y-21317D01*
Y-21371D01*
Y-21425D01*
Y-21479D01*
Y-21533D01*
Y-21587D01*
Y-21642D01*
Y-21696D01*
Y-21750D01*
Y-21804D01*
Y-21858D01*
Y-21912D01*
Y-21966D01*
Y-22020D01*
Y-22074D01*
Y-22128D01*
Y-22182D01*
Y-22236D01*
Y-22290D01*
Y-22344D01*
Y-22398D01*
Y-22452D01*
Y-22506D01*
Y-22561D01*
Y-22615D01*
Y-22669D01*
Y-22723D01*
Y-22777D01*
Y-22831D01*
Y-22885D01*
Y-22939D01*
Y-22993D01*
Y-23047D01*
Y-23101D01*
Y-23155D01*
Y-23209D01*
Y-23263D01*
Y-23317D01*
Y-23371D01*
Y-23426D01*
Y-23480D01*
Y-23534D01*
Y-23588D01*
Y-23642D01*
Y-23696D01*
Y-23750D01*
Y-23804D01*
Y-23858D01*
Y-23912D01*
Y-23966D01*
Y-24020D01*
Y-24074D01*
Y-24128D01*
Y-24182D01*
Y-24237D01*
Y-24291D01*
Y-24345D01*
Y-24399D01*
Y-24453D01*
Y-24507D01*
Y-24561D01*
Y-24615D01*
Y-24669D01*
Y-24723D01*
Y-24777D01*
Y-24831D01*
Y-24885D01*
Y-24939D01*
Y-24993D01*
Y-25047D01*
Y-25102D01*
Y-25155D01*
Y-25210D01*
Y-25264D01*
Y-25318D01*
Y-25372D01*
Y-25426D01*
Y-25480D01*
Y-25534D01*
Y-25588D01*
Y-25642D01*
Y-25696D01*
Y-25750D01*
Y-25804D01*
Y-25858D01*
Y-25912D01*
Y-25967D01*
Y-26021D01*
Y-26075D01*
Y-26129D01*
Y-26183D01*
Y-26237D01*
Y-26291D01*
Y-26345D01*
Y-26399D01*
Y-26453D01*
Y-26507D01*
Y-26561D01*
Y-26615D01*
Y-26669D01*
Y-26723D01*
Y-26777D01*
Y-26831D01*
Y-26886D01*
Y-26940D01*
Y-26994D01*
Y-27048D01*
Y-27102D01*
Y-27156D01*
Y-27210D01*
Y-27264D01*
Y-27318D01*
Y-27372D01*
Y-27426D01*
Y-27480D01*
Y-27534D01*
Y-27588D01*
Y-27642D01*
Y-27696D01*
Y-27751D01*
Y-27805D01*
Y-27859D01*
Y-27913D01*
Y-27967D01*
Y-28021D01*
Y-28075D01*
Y-28129D01*
Y-28183D01*
Y-28237D01*
Y-28291D01*
Y-28345D01*
Y-28399D01*
Y-28453D01*
Y-28507D01*
Y-28561D01*
Y-28615D01*
Y-28670D01*
Y-28724D01*
Y-28778D01*
Y-28832D01*
Y-28886D01*
Y-28940D01*
Y-28994D01*
Y-29048D01*
Y-29102D01*
Y-29156D01*
Y-29210D01*
Y-29264D01*
Y-29318D01*
X390108D01*
Y-29372D01*
Y-29426D01*
Y-29480D01*
Y-29535D01*
Y-29589D01*
Y-29643D01*
Y-29697D01*
Y-29751D01*
Y-29805D01*
Y-29859D01*
Y-29913D01*
Y-29967D01*
Y-30021D01*
Y-30075D01*
Y-30129D01*
Y-30183D01*
Y-30237D01*
Y-30291D01*
Y-30345D01*
Y-30400D01*
Y-30454D01*
Y-30508D01*
Y-30562D01*
Y-30616D01*
Y-30670D01*
Y-30724D01*
Y-30778D01*
Y-30832D01*
Y-30886D01*
Y-30940D01*
Y-30994D01*
Y-31048D01*
Y-31102D01*
Y-31156D01*
Y-31211D01*
Y-31265D01*
Y-31319D01*
Y-31373D01*
Y-31427D01*
Y-31481D01*
Y-31535D01*
Y-31589D01*
Y-31643D01*
Y-31697D01*
Y-31751D01*
Y-31805D01*
Y-31859D01*
Y-31913D01*
Y-31967D01*
Y-32021D01*
Y-32076D01*
Y-32129D01*
Y-32184D01*
Y-32238D01*
Y-32292D01*
Y-32346D01*
Y-32400D01*
Y-32454D01*
Y-32508D01*
Y-32562D01*
Y-32616D01*
Y-32670D01*
Y-32724D01*
Y-32778D01*
Y-32832D01*
Y-32886D01*
Y-32941D01*
Y-32994D01*
Y-33049D01*
Y-33103D01*
Y-33157D01*
Y-33211D01*
Y-33265D01*
Y-33319D01*
Y-33373D01*
Y-33427D01*
Y-33481D01*
Y-33535D01*
Y-33589D01*
Y-33643D01*
Y-33697D01*
Y-33751D01*
Y-33806D01*
Y-33860D01*
Y-33914D01*
Y-33968D01*
Y-34022D01*
Y-34076D01*
Y-34130D01*
Y-34184D01*
Y-34238D01*
Y-34292D01*
Y-34346D01*
Y-34400D01*
Y-34454D01*
Y-34508D01*
Y-34562D01*
Y-34616D01*
Y-34670D01*
Y-34725D01*
Y-34779D01*
Y-34833D01*
Y-34887D01*
Y-34941D01*
Y-34995D01*
Y-35049D01*
Y-35103D01*
Y-35157D01*
Y-35211D01*
Y-35265D01*
X395298D01*
Y-35319D01*
X395352D01*
Y-35373D01*
Y-35427D01*
Y-35481D01*
Y-35535D01*
Y-35590D01*
Y-35644D01*
Y-35698D01*
Y-35752D01*
Y-35806D01*
Y-35860D01*
Y-35914D01*
Y-35968D01*
Y-36022D01*
Y-36076D01*
Y-36130D01*
Y-36184D01*
Y-36238D01*
Y-36292D01*
Y-36346D01*
Y-36400D01*
Y-36454D01*
Y-36509D01*
Y-36563D01*
Y-36617D01*
X390108D01*
Y-36671D01*
Y-36725D01*
Y-36779D01*
Y-36833D01*
Y-36887D01*
Y-36941D01*
Y-36995D01*
Y-37049D01*
Y-37103D01*
Y-37157D01*
Y-37211D01*
Y-37265D01*
Y-37319D01*
Y-37374D01*
Y-37428D01*
Y-37482D01*
Y-37536D01*
Y-37590D01*
Y-37644D01*
Y-37698D01*
Y-37752D01*
Y-37806D01*
Y-37860D01*
Y-37914D01*
Y-37968D01*
Y-38022D01*
Y-38076D01*
Y-38130D01*
Y-38184D01*
Y-38238D01*
Y-38293D01*
Y-38347D01*
Y-38401D01*
Y-38455D01*
Y-38509D01*
Y-38563D01*
Y-38617D01*
Y-38671D01*
Y-38725D01*
Y-38779D01*
Y-38833D01*
Y-38887D01*
Y-38941D01*
Y-38995D01*
Y-39050D01*
Y-39103D01*
Y-39158D01*
Y-39212D01*
Y-39266D01*
Y-39320D01*
Y-39374D01*
Y-39428D01*
Y-39482D01*
Y-39536D01*
Y-39590D01*
Y-39644D01*
Y-39698D01*
Y-39752D01*
Y-39806D01*
Y-39860D01*
Y-39915D01*
Y-39968D01*
Y-40023D01*
Y-40077D01*
Y-40131D01*
Y-40185D01*
Y-40239D01*
Y-40293D01*
Y-40347D01*
Y-40401D01*
Y-40455D01*
Y-40509D01*
Y-40563D01*
Y-40617D01*
Y-40671D01*
Y-40725D01*
Y-40780D01*
Y-40834D01*
Y-40888D01*
Y-40942D01*
Y-40996D01*
Y-41050D01*
Y-41104D01*
Y-41158D01*
Y-41212D01*
Y-41266D01*
Y-41320D01*
Y-41374D01*
Y-41428D01*
Y-41482D01*
Y-41536D01*
Y-41590D01*
Y-41644D01*
Y-41699D01*
Y-41753D01*
Y-41807D01*
Y-41861D01*
Y-41915D01*
Y-41969D01*
Y-42023D01*
Y-42077D01*
Y-42131D01*
Y-42185D01*
Y-42239D01*
Y-42293D01*
Y-42347D01*
Y-42401D01*
Y-42455D01*
Y-42509D01*
Y-42564D01*
Y-42618D01*
X395352D01*
Y-42672D01*
Y-42726D01*
Y-42780D01*
Y-42834D01*
Y-42888D01*
Y-42942D01*
Y-42996D01*
Y-43050D01*
Y-43104D01*
Y-43158D01*
Y-43212D01*
Y-43266D01*
Y-43320D01*
Y-43374D01*
Y-43429D01*
Y-43483D01*
Y-43537D01*
Y-43591D01*
Y-43645D01*
Y-43699D01*
Y-43753D01*
Y-43807D01*
Y-43861D01*
Y-43915D01*
X395298D01*
Y-43969D01*
X390108D01*
Y-44023D01*
Y-44077D01*
Y-44131D01*
Y-44185D01*
Y-44239D01*
Y-44293D01*
Y-44348D01*
Y-44402D01*
Y-44456D01*
Y-44510D01*
Y-44564D01*
Y-44618D01*
Y-44672D01*
Y-44726D01*
Y-44780D01*
Y-44834D01*
Y-44888D01*
Y-44942D01*
Y-44996D01*
Y-45050D01*
Y-45104D01*
Y-45158D01*
Y-45213D01*
Y-45267D01*
Y-45321D01*
Y-45375D01*
Y-45429D01*
Y-45483D01*
Y-45537D01*
Y-45591D01*
Y-45645D01*
Y-45699D01*
Y-45753D01*
Y-45807D01*
Y-45861D01*
Y-45915D01*
Y-45969D01*
Y-46023D01*
Y-46077D01*
Y-46132D01*
Y-46186D01*
Y-46240D01*
Y-46294D01*
Y-46348D01*
Y-46402D01*
Y-46456D01*
Y-46510D01*
Y-46564D01*
Y-46618D01*
Y-46672D01*
Y-46726D01*
Y-46780D01*
Y-46834D01*
Y-46889D01*
Y-46942D01*
Y-46997D01*
Y-47051D01*
Y-47105D01*
Y-47159D01*
Y-47213D01*
Y-47267D01*
Y-47321D01*
Y-47375D01*
Y-47429D01*
Y-47483D01*
Y-47537D01*
Y-47591D01*
Y-47645D01*
Y-47699D01*
Y-47754D01*
Y-47807D01*
Y-47862D01*
Y-47916D01*
Y-47970D01*
Y-48024D01*
Y-48078D01*
Y-48132D01*
Y-48186D01*
Y-48240D01*
Y-48294D01*
Y-48348D01*
Y-48402D01*
Y-48456D01*
Y-48510D01*
Y-48564D01*
Y-48619D01*
Y-48673D01*
Y-48727D01*
Y-48781D01*
Y-48835D01*
Y-48889D01*
Y-48943D01*
Y-48997D01*
Y-49051D01*
Y-49105D01*
Y-49159D01*
Y-49213D01*
Y-49267D01*
Y-49321D01*
Y-49375D01*
Y-49429D01*
Y-49483D01*
Y-49538D01*
Y-49592D01*
Y-49646D01*
Y-49700D01*
Y-49754D01*
Y-49808D01*
Y-49862D01*
Y-49916D01*
X395352D01*
Y-49970D01*
Y-50024D01*
Y-50078D01*
Y-50132D01*
Y-50186D01*
Y-50240D01*
Y-50294D01*
Y-50348D01*
Y-50402D01*
Y-50457D01*
Y-50511D01*
Y-50565D01*
Y-50619D01*
Y-50673D01*
Y-50727D01*
Y-50781D01*
Y-50835D01*
Y-50889D01*
Y-50943D01*
Y-50997D01*
Y-51051D01*
Y-51105D01*
Y-51159D01*
Y-51213D01*
Y-51267D01*
X390108D01*
Y-51322D01*
Y-51376D01*
Y-51430D01*
Y-51484D01*
Y-51538D01*
Y-51592D01*
Y-51646D01*
Y-51700D01*
Y-51754D01*
Y-51808D01*
Y-51862D01*
Y-51916D01*
Y-51970D01*
Y-52024D01*
Y-52078D01*
Y-52132D01*
Y-52187D01*
Y-52241D01*
Y-52295D01*
Y-52349D01*
Y-52403D01*
Y-52457D01*
Y-52511D01*
Y-52565D01*
Y-52619D01*
Y-52673D01*
Y-52727D01*
Y-52781D01*
Y-52835D01*
Y-52889D01*
Y-52943D01*
Y-52997D01*
Y-53052D01*
Y-53106D01*
Y-53160D01*
Y-53214D01*
Y-53268D01*
Y-53322D01*
Y-53376D01*
Y-53430D01*
Y-53484D01*
Y-53538D01*
Y-53592D01*
Y-53646D01*
Y-53700D01*
Y-53754D01*
Y-53808D01*
Y-53863D01*
Y-53917D01*
Y-53971D01*
Y-54025D01*
Y-54079D01*
Y-54133D01*
Y-54187D01*
Y-54241D01*
Y-54295D01*
Y-54349D01*
Y-54403D01*
Y-54457D01*
Y-54511D01*
Y-54565D01*
Y-54619D01*
Y-54673D01*
Y-54728D01*
Y-54782D01*
Y-54836D01*
Y-54890D01*
Y-54944D01*
Y-54998D01*
Y-55052D01*
Y-55106D01*
Y-55160D01*
Y-55214D01*
Y-55268D01*
Y-55322D01*
Y-55376D01*
Y-55430D01*
Y-55484D01*
Y-55538D01*
Y-55592D01*
Y-55647D01*
Y-55701D01*
Y-55755D01*
Y-55809D01*
Y-55863D01*
Y-55917D01*
Y-55971D01*
Y-56025D01*
Y-56079D01*
Y-56133D01*
Y-56187D01*
Y-56241D01*
Y-56295D01*
Y-56349D01*
Y-56403D01*
Y-56457D01*
Y-56511D01*
Y-56566D01*
Y-56620D01*
Y-56674D01*
Y-56728D01*
Y-56782D01*
Y-56836D01*
Y-56890D01*
Y-56944D01*
Y-56998D01*
Y-57052D01*
Y-57106D01*
Y-57160D01*
Y-57214D01*
X395352D01*
Y-57268D01*
Y-57322D01*
Y-57376D01*
Y-57431D01*
Y-57485D01*
Y-57539D01*
Y-57593D01*
Y-57647D01*
Y-57701D01*
Y-57755D01*
Y-57809D01*
Y-57863D01*
Y-57917D01*
Y-57971D01*
Y-58025D01*
Y-58079D01*
Y-58133D01*
Y-58187D01*
Y-58241D01*
Y-58296D01*
Y-58350D01*
Y-58404D01*
Y-58458D01*
Y-58512D01*
Y-58566D01*
Y-58620D01*
Y-58674D01*
Y-58728D01*
Y-58782D01*
Y-58836D01*
Y-58890D01*
Y-58944D01*
Y-58998D01*
Y-59052D01*
Y-59106D01*
Y-59161D01*
Y-59215D01*
Y-59269D01*
Y-59323D01*
Y-59377D01*
Y-59431D01*
Y-59485D01*
Y-59539D01*
Y-59593D01*
Y-59647D01*
Y-59701D01*
Y-59755D01*
Y-59809D01*
Y-59863D01*
Y-59917D01*
Y-59971D01*
Y-60026D01*
Y-60080D01*
Y-60134D01*
Y-60188D01*
Y-60242D01*
Y-60296D01*
Y-60350D01*
Y-60404D01*
Y-60458D01*
Y-60512D01*
Y-60566D01*
Y-60620D01*
Y-60674D01*
Y-60728D01*
Y-60782D01*
Y-60836D01*
Y-60891D01*
Y-60945D01*
Y-60999D01*
Y-61053D01*
Y-61107D01*
Y-61161D01*
Y-61215D01*
Y-61269D01*
Y-61323D01*
Y-61377D01*
Y-61431D01*
Y-61485D01*
Y-61539D01*
Y-61593D01*
Y-61647D01*
Y-61702D01*
Y-61756D01*
Y-61810D01*
Y-61864D01*
Y-61918D01*
Y-61972D01*
Y-62026D01*
Y-62080D01*
X387297D01*
Y-62026D01*
Y-61972D01*
Y-61918D01*
Y-61864D01*
Y-61810D01*
Y-61756D01*
Y-61702D01*
Y-61647D01*
Y-61593D01*
Y-61539D01*
Y-61485D01*
Y-61431D01*
Y-61377D01*
Y-61323D01*
Y-61269D01*
Y-61215D01*
Y-61161D01*
Y-61107D01*
Y-61053D01*
Y-60999D01*
Y-60945D01*
Y-60891D01*
Y-60836D01*
Y-60782D01*
Y-60728D01*
Y-60674D01*
Y-60620D01*
Y-60566D01*
Y-60512D01*
Y-60458D01*
Y-60404D01*
Y-60350D01*
Y-60296D01*
Y-60242D01*
Y-60188D01*
Y-60134D01*
Y-60080D01*
Y-60026D01*
Y-59971D01*
Y-59917D01*
Y-59863D01*
Y-59809D01*
Y-59755D01*
Y-59701D01*
Y-59647D01*
Y-59593D01*
Y-59539D01*
Y-59485D01*
Y-59431D01*
Y-59377D01*
Y-59323D01*
Y-59269D01*
Y-59215D01*
Y-59161D01*
Y-59106D01*
Y-59052D01*
Y-58998D01*
Y-58944D01*
Y-58890D01*
Y-58836D01*
Y-58782D01*
Y-58728D01*
Y-58674D01*
Y-58620D01*
Y-58566D01*
Y-58512D01*
Y-58458D01*
Y-58404D01*
Y-58350D01*
Y-58296D01*
Y-58241D01*
Y-58187D01*
Y-58133D01*
Y-58079D01*
Y-58025D01*
Y-57971D01*
Y-57917D01*
Y-57863D01*
Y-57809D01*
Y-57755D01*
Y-57701D01*
Y-57647D01*
Y-57593D01*
Y-57539D01*
Y-57485D01*
Y-57431D01*
Y-57376D01*
X387242D01*
Y-57322D01*
Y-57268D01*
X387188D01*
Y-57214D01*
X387134D01*
Y-57160D01*
X387080D01*
Y-57106D01*
X386972D01*
Y-57052D01*
X378592D01*
Y-57106D01*
X378484D01*
Y-57160D01*
X378376D01*
Y-57214D01*
X378322D01*
Y-57268D01*
Y-57322D01*
X378268D01*
Y-57376D01*
Y-57431D01*
Y-57485D01*
Y-57539D01*
Y-57593D01*
Y-57647D01*
X378214D01*
Y-57701D01*
X378268D01*
Y-57755D01*
X378214D01*
Y-57809D01*
Y-57863D01*
X378268D01*
Y-57917D01*
Y-57971D01*
Y-58025D01*
Y-58079D01*
Y-58133D01*
Y-58187D01*
Y-58241D01*
Y-58296D01*
Y-58350D01*
Y-58404D01*
Y-58458D01*
Y-58512D01*
Y-58566D01*
Y-58620D01*
Y-58674D01*
Y-58728D01*
Y-58782D01*
Y-58836D01*
Y-58890D01*
Y-58944D01*
Y-58998D01*
Y-59052D01*
Y-59106D01*
Y-59161D01*
Y-59215D01*
Y-59269D01*
Y-59323D01*
Y-59377D01*
Y-59431D01*
Y-59485D01*
Y-59539D01*
Y-59593D01*
Y-59647D01*
Y-59701D01*
Y-59755D01*
Y-59809D01*
Y-59863D01*
Y-59917D01*
Y-59971D01*
Y-60026D01*
Y-60080D01*
Y-60134D01*
Y-60188D01*
Y-60242D01*
Y-60296D01*
Y-60350D01*
Y-60404D01*
Y-60458D01*
Y-60512D01*
Y-60566D01*
Y-60620D01*
X378214D01*
Y-60674D01*
Y-60728D01*
Y-60782D01*
X378160D01*
Y-60836D01*
X378106D01*
Y-60891D01*
X378052D01*
Y-60945D01*
X377998D01*
Y-60999D01*
X377836D01*
Y-61053D01*
X374592D01*
Y-60999D01*
X374430D01*
Y-60945D01*
X374376D01*
Y-60891D01*
X374322D01*
Y-60836D01*
X374268D01*
Y-60782D01*
X374214D01*
Y-60728D01*
Y-60674D01*
Y-60620D01*
Y-60566D01*
X374159D01*
Y-60512D01*
Y-60458D01*
Y-60404D01*
Y-60350D01*
Y-60296D01*
Y-60242D01*
Y-60188D01*
Y-60134D01*
Y-60080D01*
Y-60026D01*
Y-59971D01*
Y-59917D01*
Y-59863D01*
Y-59809D01*
Y-59755D01*
Y-59701D01*
Y-59647D01*
Y-59593D01*
Y-59539D01*
Y-59485D01*
Y-59431D01*
Y-59377D01*
Y-59323D01*
Y-59269D01*
Y-59215D01*
Y-59161D01*
Y-59106D01*
Y-59052D01*
Y-58998D01*
Y-58944D01*
Y-58890D01*
Y-58836D01*
Y-58782D01*
Y-58728D01*
Y-58674D01*
Y-58620D01*
Y-58566D01*
Y-58512D01*
Y-58458D01*
Y-58404D01*
Y-58350D01*
Y-58296D01*
Y-58241D01*
X374214D01*
Y-58187D01*
X374159D01*
Y-58133D01*
Y-58079D01*
X374214D01*
Y-58025D01*
X374159D01*
Y-57971D01*
Y-57917D01*
Y-57863D01*
Y-57809D01*
Y-57755D01*
Y-57701D01*
X374105D01*
Y-57647D01*
Y-57593D01*
X374051D01*
Y-57539D01*
Y-57485D01*
X373997D01*
Y-57431D01*
X373943D01*
Y-57376D01*
X373889D01*
Y-57322D01*
X373835D01*
Y-57268D01*
X373781D01*
Y-57214D01*
X373673D01*
Y-57160D01*
X373565D01*
Y-57106D01*
X373403D01*
Y-57052D01*
X372970D01*
Y-57106D01*
X372808D01*
Y-57160D01*
X372700D01*
Y-57214D01*
X372592D01*
Y-57268D01*
X372538D01*
Y-57322D01*
X372483D01*
Y-57376D01*
X372429D01*
Y-57431D01*
X372375D01*
Y-57485D01*
Y-57539D01*
X372321D01*
Y-57593D01*
Y-57647D01*
X372267D01*
Y-57701D01*
Y-57755D01*
X372213D01*
Y-57809D01*
Y-57863D01*
Y-57917D01*
Y-57971D01*
Y-58025D01*
Y-58079D01*
Y-58133D01*
Y-58187D01*
Y-58241D01*
X372159D01*
Y-58296D01*
X372213D01*
Y-58350D01*
Y-58404D01*
Y-58458D01*
Y-58512D01*
Y-58566D01*
Y-58620D01*
Y-58674D01*
Y-58728D01*
Y-58782D01*
Y-58836D01*
Y-58890D01*
Y-58944D01*
Y-58998D01*
Y-59052D01*
Y-59106D01*
Y-59161D01*
Y-59215D01*
Y-59269D01*
Y-59323D01*
Y-59377D01*
Y-59431D01*
Y-59485D01*
Y-59539D01*
Y-59593D01*
Y-59647D01*
Y-59701D01*
Y-59755D01*
Y-59809D01*
Y-59863D01*
Y-59917D01*
Y-59971D01*
Y-60026D01*
Y-60080D01*
Y-60134D01*
Y-60188D01*
Y-60242D01*
Y-60296D01*
Y-60350D01*
Y-60404D01*
Y-60458D01*
Y-60512D01*
Y-60566D01*
Y-60620D01*
Y-60674D01*
Y-60728D01*
Y-60782D01*
Y-60836D01*
Y-60891D01*
Y-60945D01*
Y-60999D01*
Y-61053D01*
Y-61107D01*
Y-61161D01*
Y-61215D01*
Y-61269D01*
Y-61323D01*
Y-61377D01*
Y-61431D01*
Y-61485D01*
Y-61539D01*
Y-61593D01*
Y-61647D01*
Y-61702D01*
Y-61756D01*
Y-61810D01*
Y-61864D01*
Y-61918D01*
Y-61972D01*
Y-62026D01*
Y-62080D01*
Y-62134D01*
Y-62188D01*
Y-62242D01*
Y-62296D01*
Y-62350D01*
Y-62404D01*
Y-62458D01*
Y-62512D01*
Y-62566D01*
Y-62621D01*
Y-62675D01*
X372159D01*
Y-62729D01*
Y-62783D01*
Y-62837D01*
X372105D01*
Y-62891D01*
Y-62945D01*
X372051D01*
Y-62999D01*
X371943D01*
Y-63053D01*
X371835D01*
Y-63107D01*
X366537D01*
Y-63053D01*
X366374D01*
Y-62999D01*
X366320D01*
Y-62945D01*
X366266D01*
Y-62891D01*
X366212D01*
Y-62837D01*
X366158D01*
Y-62783D01*
Y-62729D01*
Y-62675D01*
Y-62621D01*
Y-62566D01*
Y-62512D01*
Y-62458D01*
Y-62404D01*
Y-62350D01*
Y-62296D01*
Y-62242D01*
Y-62188D01*
Y-62134D01*
Y-62080D01*
Y-62026D01*
Y-61972D01*
Y-61918D01*
Y-61864D01*
Y-61810D01*
Y-61756D01*
Y-61702D01*
Y-61647D01*
Y-61593D01*
Y-61539D01*
Y-61485D01*
Y-61431D01*
Y-61377D01*
Y-61323D01*
Y-61269D01*
Y-61215D01*
Y-61161D01*
Y-61107D01*
Y-61053D01*
Y-60999D01*
Y-60945D01*
Y-60891D01*
Y-60836D01*
Y-60782D01*
Y-60728D01*
Y-60674D01*
Y-60620D01*
Y-60566D01*
Y-60512D01*
Y-60458D01*
Y-60404D01*
Y-60350D01*
Y-60296D01*
Y-60242D01*
Y-60188D01*
Y-60134D01*
Y-60080D01*
Y-60026D01*
Y-59971D01*
Y-59917D01*
Y-59863D01*
Y-59809D01*
Y-59755D01*
Y-59701D01*
Y-59647D01*
Y-59593D01*
Y-59539D01*
X366104D01*
Y-59485D01*
Y-59431D01*
Y-59377D01*
Y-59323D01*
X366050D01*
Y-59269D01*
X365996D01*
Y-59215D01*
X365942D01*
Y-59161D01*
X365888D01*
Y-59106D01*
X365726D01*
Y-59052D01*
X365564D01*
Y-59106D01*
X365401D01*
Y-59161D01*
X365293D01*
Y-59215D01*
X365239D01*
Y-59269D01*
Y-59323D01*
X365185D01*
Y-59377D01*
Y-59431D01*
Y-59485D01*
X365131D01*
Y-59539D01*
Y-59593D01*
Y-59647D01*
Y-59701D01*
Y-59755D01*
Y-59809D01*
Y-59863D01*
Y-59917D01*
Y-59971D01*
Y-60026D01*
Y-60080D01*
Y-60134D01*
Y-60188D01*
Y-60242D01*
Y-60296D01*
Y-60350D01*
Y-60404D01*
Y-60458D01*
Y-60512D01*
Y-60566D01*
Y-60620D01*
Y-60674D01*
Y-60728D01*
Y-60782D01*
Y-60836D01*
Y-60891D01*
Y-60945D01*
Y-60999D01*
Y-61053D01*
Y-61107D01*
Y-61161D01*
Y-61215D01*
Y-61269D01*
Y-61323D01*
Y-61377D01*
Y-61431D01*
Y-61485D01*
Y-61539D01*
Y-61593D01*
Y-61647D01*
Y-61702D01*
Y-61756D01*
Y-61810D01*
Y-61864D01*
Y-61918D01*
Y-61972D01*
Y-62026D01*
Y-62080D01*
Y-62134D01*
Y-62188D01*
Y-62242D01*
Y-62296D01*
Y-62350D01*
Y-62404D01*
Y-62458D01*
Y-62512D01*
Y-62566D01*
Y-62621D01*
Y-62675D01*
Y-62729D01*
Y-62783D01*
X365077D01*
Y-62837D01*
Y-62891D01*
X365023D01*
Y-62945D01*
X364969D01*
Y-62999D01*
X364915D01*
Y-63053D01*
X364753D01*
Y-63107D01*
X354427D01*
Y-63053D01*
X354319D01*
Y-62999D01*
X354211D01*
Y-62945D01*
X354156D01*
Y-62891D01*
Y-62837D01*
X354102D01*
Y-62783D01*
Y-62729D01*
X354048D01*
Y-62675D01*
Y-62621D01*
Y-62566D01*
Y-62512D01*
Y-62458D01*
Y-62404D01*
Y-62350D01*
Y-62296D01*
Y-62242D01*
Y-62188D01*
Y-62134D01*
Y-62080D01*
Y-62026D01*
Y-61972D01*
Y-61918D01*
Y-61864D01*
Y-61810D01*
Y-61756D01*
Y-61702D01*
Y-61647D01*
Y-61593D01*
Y-61539D01*
Y-61485D01*
Y-61431D01*
Y-61377D01*
Y-61323D01*
Y-61269D01*
Y-61215D01*
Y-61161D01*
Y-61107D01*
Y-61053D01*
Y-60999D01*
Y-60945D01*
Y-60891D01*
Y-60836D01*
Y-60782D01*
Y-60728D01*
Y-60674D01*
Y-60620D01*
Y-60566D01*
Y-60512D01*
Y-60458D01*
Y-60404D01*
Y-60350D01*
Y-60296D01*
Y-60242D01*
Y-60188D01*
Y-60134D01*
Y-60080D01*
Y-60026D01*
Y-59971D01*
Y-59917D01*
Y-59863D01*
Y-59809D01*
Y-59755D01*
Y-59701D01*
Y-59647D01*
Y-59593D01*
Y-59539D01*
Y-59485D01*
Y-59431D01*
Y-59377D01*
Y-59323D01*
Y-59269D01*
Y-59215D01*
Y-59161D01*
Y-59106D01*
Y-59052D01*
Y-58998D01*
Y-58944D01*
Y-58890D01*
Y-58836D01*
Y-58782D01*
Y-58728D01*
Y-58674D01*
Y-58620D01*
Y-58566D01*
Y-58512D01*
Y-58458D01*
Y-58404D01*
Y-58350D01*
Y-58296D01*
Y-58241D01*
Y-58187D01*
Y-58133D01*
Y-58079D01*
Y-58025D01*
Y-57971D01*
Y-57917D01*
Y-57863D01*
Y-57809D01*
Y-57755D01*
Y-57701D01*
Y-57647D01*
Y-57593D01*
Y-57539D01*
Y-57485D01*
Y-57431D01*
Y-57376D01*
X353994D01*
Y-57322D01*
Y-57268D01*
X353940D01*
Y-57214D01*
X353886D01*
Y-57160D01*
X353832D01*
Y-57106D01*
X353724D01*
Y-57052D01*
X314799D01*
Y-56998D01*
X314583D01*
Y-56944D01*
X314421D01*
Y-56890D01*
X314313D01*
Y-56836D01*
X314205D01*
Y-56782D01*
X314096D01*
Y-56728D01*
X313988D01*
Y-56674D01*
X313934D01*
Y-56620D01*
X313826D01*
Y-56566D01*
X313772D01*
Y-56511D01*
X313718D01*
Y-56457D01*
X313610D01*
Y-56403D01*
X313556D01*
Y-56349D01*
X313502D01*
Y-56295D01*
X313448D01*
Y-56241D01*
X313394D01*
Y-56187D01*
X313340D01*
Y-56133D01*
X313286D01*
Y-56079D01*
X313232D01*
Y-56025D01*
X313177D01*
Y-55971D01*
X313123D01*
Y-55917D01*
X313069D01*
Y-55863D01*
Y-55809D01*
X313015D01*
Y-55755D01*
X312961D01*
Y-55701D01*
X312907D01*
Y-55647D01*
Y-55592D01*
X312853D01*
Y-55538D01*
X312799D01*
Y-55484D01*
Y-55430D01*
X312745D01*
Y-55376D01*
X312691D01*
Y-55322D01*
Y-55268D01*
X312637D01*
Y-55214D01*
Y-55160D01*
X312583D01*
Y-55106D01*
Y-55052D01*
X312529D01*
Y-54998D01*
Y-54944D01*
Y-54890D01*
X312475D01*
Y-54836D01*
Y-54782D01*
Y-54728D01*
X312421D01*
Y-54673D01*
Y-54619D01*
Y-54565D01*
X312367D01*
Y-54511D01*
Y-54457D01*
Y-54403D01*
X312313D01*
Y-54349D01*
Y-54295D01*
Y-54241D01*
Y-54187D01*
Y-54133D01*
X312258D01*
Y-54079D01*
Y-54025D01*
Y-53971D01*
Y-53917D01*
Y-53863D01*
Y-53808D01*
Y-53754D01*
Y-53700D01*
Y-53646D01*
Y-53592D01*
X312204D01*
Y-53538D01*
Y-53484D01*
X312258D01*
Y-53430D01*
Y-53376D01*
Y-53322D01*
Y-53268D01*
Y-53214D01*
Y-53160D01*
Y-53106D01*
Y-53052D01*
Y-52997D01*
X312313D01*
Y-52943D01*
Y-52889D01*
Y-52835D01*
Y-52781D01*
Y-52727D01*
Y-52673D01*
X312367D01*
Y-52619D01*
Y-52565D01*
Y-52511D01*
X312421D01*
Y-52457D01*
Y-52403D01*
Y-52349D01*
X312475D01*
Y-52295D01*
Y-52241D01*
Y-52187D01*
X312529D01*
Y-52132D01*
Y-52078D01*
X312583D01*
Y-52024D01*
Y-51970D01*
X312637D01*
Y-51916D01*
Y-51862D01*
X312691D01*
Y-51808D01*
Y-51754D01*
X312745D01*
Y-51700D01*
X312799D01*
Y-51646D01*
Y-51592D01*
X312853D01*
Y-51538D01*
X312907D01*
Y-51484D01*
Y-51430D01*
X312961D01*
Y-51376D01*
X313015D01*
Y-51322D01*
X313069D01*
Y-51267D01*
X313123D01*
Y-51213D01*
Y-51159D01*
X313177D01*
Y-51105D01*
X313232D01*
Y-51051D01*
X313286D01*
Y-50997D01*
X313340D01*
Y-50943D01*
X313394D01*
Y-50889D01*
X313502D01*
Y-50835D01*
X313556D01*
Y-50781D01*
X313610D01*
Y-50727D01*
X313664D01*
Y-50673D01*
X313772D01*
Y-50619D01*
X313826D01*
Y-50565D01*
X313934D01*
Y-50511D01*
X314042D01*
Y-50457D01*
X314096D01*
Y-50402D01*
X314205D01*
Y-50348D01*
X314313D01*
Y-50294D01*
X314475D01*
Y-50240D01*
X314637D01*
Y-50186D01*
X314799D01*
Y-50132D01*
X314962D01*
Y-50078D01*
X315232D01*
Y-50024D01*
X326423D01*
Y-49970D01*
X326909D01*
Y-49916D01*
X327180D01*
Y-49862D01*
X327396D01*
Y-49808D01*
X327504D01*
Y-49754D01*
X327666D01*
Y-49700D01*
X327774D01*
Y-49646D01*
X327882D01*
Y-49592D01*
X327991D01*
Y-49538D01*
X328099D01*
Y-49483D01*
X328207D01*
Y-49429D01*
X328261D01*
Y-49375D01*
X328369D01*
Y-49321D01*
X328423D01*
Y-49267D01*
X328477D01*
Y-49213D01*
X328585D01*
Y-49159D01*
X328639D01*
Y-49105D01*
X328693D01*
Y-49051D01*
X328747D01*
Y-48997D01*
X328801D01*
Y-48943D01*
X328855D01*
Y-48889D01*
X328909D01*
Y-48835D01*
X328964D01*
Y-48781D01*
X329018D01*
Y-48727D01*
X329072D01*
Y-48673D01*
Y-48619D01*
X329126D01*
Y-48564D01*
X329180D01*
Y-48510D01*
X329234D01*
Y-48456D01*
Y-48402D01*
X329288D01*
Y-48348D01*
X329342D01*
Y-48294D01*
Y-48240D01*
X329396D01*
Y-48186D01*
Y-48132D01*
X329450D01*
Y-48078D01*
Y-48024D01*
X329504D01*
Y-47970D01*
Y-47916D01*
X329558D01*
Y-47862D01*
Y-47807D01*
X329612D01*
Y-47754D01*
Y-47699D01*
Y-47645D01*
X329666D01*
Y-47591D01*
Y-47537D01*
Y-47483D01*
X329720D01*
Y-47429D01*
Y-47375D01*
Y-47321D01*
X329774D01*
Y-47267D01*
Y-47213D01*
Y-47159D01*
Y-47105D01*
Y-47051D01*
X329829D01*
Y-46997D01*
Y-46942D01*
Y-46889D01*
Y-46834D01*
Y-46780D01*
Y-46726D01*
Y-46672D01*
Y-46618D01*
Y-46564D01*
Y-46510D01*
Y-46456D01*
Y-46402D01*
Y-46348D01*
Y-46294D01*
Y-46240D01*
Y-46186D01*
Y-46132D01*
Y-46077D01*
Y-46023D01*
Y-45969D01*
Y-45915D01*
X329774D01*
Y-45861D01*
Y-45807D01*
Y-45753D01*
Y-45699D01*
Y-45645D01*
X329720D01*
Y-45591D01*
Y-45537D01*
Y-45483D01*
X329666D01*
Y-45429D01*
Y-45375D01*
Y-45321D01*
X329612D01*
Y-45267D01*
Y-45213D01*
Y-45158D01*
X329558D01*
Y-45104D01*
Y-45050D01*
X329504D01*
Y-44996D01*
Y-44942D01*
X329450D01*
Y-44888D01*
Y-44834D01*
X329396D01*
Y-44780D01*
Y-44726D01*
X329342D01*
Y-44672D01*
X329288D01*
Y-44618D01*
Y-44564D01*
X329234D01*
Y-44510D01*
X329180D01*
Y-44456D01*
Y-44402D01*
X329126D01*
Y-44348D01*
X329072D01*
Y-44293D01*
X329018D01*
Y-44239D01*
X328964D01*
Y-44185D01*
Y-44131D01*
X328909D01*
Y-44077D01*
X328855D01*
Y-44023D01*
X328801D01*
Y-43969D01*
X328747D01*
Y-43915D01*
X328693D01*
Y-43861D01*
X328585D01*
Y-43807D01*
X328531D01*
Y-43753D01*
X328477D01*
Y-43699D01*
X328423D01*
Y-43645D01*
X328315D01*
Y-43591D01*
X328261D01*
Y-43537D01*
X328153D01*
Y-43483D01*
X328045D01*
Y-43429D01*
X327991D01*
Y-43374D01*
X327882D01*
Y-43320D01*
X327774D01*
Y-43266D01*
X327612D01*
Y-43212D01*
X327504D01*
Y-43158D01*
X327342D01*
Y-43104D01*
X327126D01*
Y-43050D01*
X326855D01*
Y-42996D01*
X326315D01*
Y-42942D01*
X326260D01*
Y-42996D01*
X310042D01*
Y-42942D01*
X309988D01*
Y-42996D01*
X309880D01*
Y-42942D01*
X309501D01*
Y-42888D01*
X309231D01*
Y-42834D01*
X309069D01*
Y-42780D01*
X308907D01*
Y-42726D01*
X308744D01*
Y-42672D01*
X308636D01*
Y-42618D01*
X308528D01*
Y-42564D01*
X308420D01*
Y-42509D01*
X308312D01*
Y-42455D01*
X308258D01*
Y-42401D01*
X308150D01*
Y-42347D01*
X308096D01*
Y-42293D01*
X307987D01*
Y-42239D01*
X307933D01*
Y-42185D01*
X307879D01*
Y-42131D01*
X307771D01*
Y-42077D01*
X307717D01*
Y-42023D01*
X307663D01*
Y-41969D01*
X307609D01*
Y-41915D01*
X307555D01*
Y-41861D01*
X307501D01*
Y-41807D01*
X307447D01*
Y-41753D01*
X307393D01*
Y-41699D01*
Y-41644D01*
X307339D01*
Y-41590D01*
X307285D01*
Y-41536D01*
X307231D01*
Y-41482D01*
X307177D01*
Y-41428D01*
Y-41374D01*
X307122D01*
Y-41320D01*
X307068D01*
Y-41266D01*
Y-41212D01*
X307014D01*
Y-41158D01*
Y-41104D01*
X306960D01*
Y-41050D01*
Y-40996D01*
X306906D01*
Y-40942D01*
Y-40888D01*
X306852D01*
Y-40834D01*
Y-40780D01*
X306798D01*
Y-40725D01*
Y-40671D01*
Y-40617D01*
X306744D01*
Y-40563D01*
Y-40509D01*
Y-40455D01*
X306690D01*
Y-40401D01*
Y-40347D01*
Y-40293D01*
X306636D01*
Y-40239D01*
Y-40185D01*
Y-40131D01*
Y-40077D01*
Y-40023D01*
X306582D01*
Y-39968D01*
Y-39915D01*
Y-39860D01*
Y-39806D01*
Y-39752D01*
Y-39698D01*
Y-39644D01*
Y-39590D01*
Y-39536D01*
Y-39482D01*
Y-39428D01*
Y-39374D01*
Y-39320D01*
Y-39266D01*
Y-39212D01*
Y-39158D01*
Y-39103D01*
Y-39050D01*
Y-38995D01*
Y-38941D01*
Y-38887D01*
X306636D01*
Y-38833D01*
Y-38779D01*
Y-38725D01*
Y-38671D01*
Y-38617D01*
X306690D01*
Y-38563D01*
Y-38509D01*
Y-38455D01*
Y-38401D01*
X306744D01*
Y-38347D01*
Y-38293D01*
Y-38238D01*
X306798D01*
Y-38184D01*
Y-38130D01*
X306852D01*
Y-38076D01*
Y-38022D01*
Y-37968D01*
X306906D01*
Y-37914D01*
Y-37860D01*
X306960D01*
Y-37806D01*
Y-37752D01*
X307014D01*
Y-37698D01*
X307068D01*
Y-37644D01*
Y-37590D01*
X307122D01*
Y-37536D01*
Y-37482D01*
X307177D01*
Y-37428D01*
X307231D01*
Y-37374D01*
X307285D01*
Y-37319D01*
Y-37265D01*
X307339D01*
Y-37211D01*
X307393D01*
Y-37157D01*
X307447D01*
Y-37103D01*
X307501D01*
Y-37049D01*
X307555D01*
Y-36995D01*
X307609D01*
Y-36941D01*
X307663D01*
Y-36887D01*
X307717D01*
Y-36833D01*
X307771D01*
Y-36779D01*
X307825D01*
Y-36725D01*
X307879D01*
Y-36671D01*
X307987D01*
Y-36617D01*
X308042D01*
Y-36563D01*
X308096D01*
Y-36509D01*
X308204D01*
Y-36454D01*
X308258D01*
Y-36400D01*
X308366D01*
Y-36346D01*
X308474D01*
Y-36292D01*
X308582D01*
Y-36238D01*
X308690D01*
Y-36184D01*
X308853D01*
Y-36130D01*
X309015D01*
Y-36076D01*
X309177D01*
Y-36022D01*
X309393D01*
Y-35968D01*
X309664D01*
Y-35914D01*
X320043D01*
Y-35860D01*
X320422D01*
Y-35806D01*
X320638D01*
Y-35752D01*
X320800D01*
Y-35698D01*
X320962D01*
Y-35644D01*
X321071D01*
Y-35590D01*
X321233D01*
Y-35535D01*
X321341D01*
Y-35481D01*
X321395D01*
Y-35427D01*
X321503D01*
Y-35373D01*
X321611D01*
Y-35319D01*
X321665D01*
Y-35265D01*
X321773D01*
Y-35211D01*
X321827D01*
Y-35157D01*
X321882D01*
Y-35103D01*
X321990D01*
Y-35049D01*
X322044D01*
Y-34995D01*
X322098D01*
Y-34941D01*
X322152D01*
Y-34887D01*
X322206D01*
Y-34833D01*
X322260D01*
Y-34779D01*
X322314D01*
Y-34725D01*
X322368D01*
Y-34670D01*
X322422D01*
Y-34616D01*
X322476D01*
Y-34562D01*
Y-34508D01*
X322530D01*
Y-34454D01*
X322584D01*
Y-34400D01*
X322638D01*
Y-34346D01*
Y-34292D01*
X322692D01*
Y-34238D01*
X322746D01*
Y-34184D01*
Y-34130D01*
X322800D01*
Y-34076D01*
Y-34022D01*
X322855D01*
Y-33968D01*
Y-33914D01*
X322909D01*
Y-33860D01*
Y-33806D01*
X322963D01*
Y-33751D01*
Y-33697D01*
X323017D01*
Y-33643D01*
Y-33589D01*
Y-33535D01*
X323071D01*
Y-33481D01*
Y-33427D01*
Y-33373D01*
X323125D01*
Y-33319D01*
Y-33265D01*
Y-33211D01*
Y-33157D01*
X323179D01*
Y-33103D01*
Y-33049D01*
Y-32994D01*
Y-32941D01*
Y-32886D01*
Y-32832D01*
X323233D01*
Y-32778D01*
Y-32724D01*
Y-32670D01*
Y-32616D01*
Y-32562D01*
Y-32508D01*
Y-32454D01*
Y-32400D01*
Y-32346D01*
Y-32292D01*
Y-32238D01*
Y-32184D01*
Y-32129D01*
Y-32076D01*
Y-32021D01*
Y-31967D01*
X323179D01*
Y-31913D01*
Y-31859D01*
Y-31805D01*
Y-31751D01*
Y-31697D01*
Y-31643D01*
X323125D01*
Y-31589D01*
Y-31535D01*
Y-31481D01*
Y-31427D01*
X323071D01*
Y-31373D01*
Y-31319D01*
Y-31265D01*
X323017D01*
Y-31211D01*
Y-31156D01*
Y-31102D01*
X322963D01*
Y-31048D01*
Y-30994D01*
X322909D01*
Y-30940D01*
Y-30886D01*
X322855D01*
Y-30832D01*
Y-30778D01*
X322800D01*
Y-30724D01*
Y-30670D01*
X322746D01*
Y-30616D01*
Y-30562D01*
X322692D01*
Y-30508D01*
X322638D01*
Y-30454D01*
Y-30400D01*
X322584D01*
Y-30345D01*
X322530D01*
Y-30291D01*
Y-30237D01*
X322476D01*
Y-30183D01*
X322422D01*
Y-30129D01*
X322368D01*
Y-30075D01*
X322314D01*
Y-30021D01*
X322260D01*
Y-29967D01*
X322206D01*
Y-29913D01*
X322152D01*
Y-29859D01*
X322098D01*
Y-29805D01*
X322044D01*
Y-29751D01*
X321990D01*
Y-29697D01*
X321936D01*
Y-29643D01*
X321827D01*
Y-29589D01*
X321773D01*
Y-29535D01*
X321719D01*
Y-29480D01*
X321611D01*
Y-29426D01*
X321557D01*
Y-29372D01*
X321449D01*
Y-29318D01*
X321341D01*
Y-29264D01*
X321233D01*
Y-29210D01*
X321125D01*
Y-29156D01*
X320962D01*
Y-29102D01*
X320854D01*
Y-29048D01*
X320638D01*
Y-28994D01*
X320422D01*
Y-28940D01*
X320097D01*
Y-28886D01*
X292039D01*
Y-28832D01*
X291715D01*
Y-28778D01*
X291499D01*
Y-28724D01*
X291336D01*
Y-28670D01*
X291174D01*
Y-28615D01*
X291066D01*
Y-28561D01*
X290958D01*
Y-28507D01*
X290796D01*
Y-28453D01*
X290742D01*
Y-28399D01*
X290634D01*
Y-28345D01*
X290526D01*
Y-28291D01*
X290471D01*
Y-28237D01*
X290363D01*
Y-28183D01*
X290309D01*
Y-28129D01*
X290255D01*
Y-28075D01*
X290147D01*
Y-28021D01*
X290093D01*
Y-27967D01*
X290039D01*
Y-27913D01*
X289985D01*
Y-27859D01*
X289931D01*
Y-27805D01*
X289877D01*
Y-27751D01*
X289823D01*
Y-27696D01*
X289769D01*
Y-27642D01*
X289715D01*
Y-27588D01*
Y-27534D01*
X289661D01*
Y-27480D01*
X289606D01*
Y-27426D01*
X289552D01*
Y-27372D01*
X289498D01*
Y-27318D01*
Y-27264D01*
X289444D01*
Y-27210D01*
X289390D01*
Y-27156D01*
Y-27102D01*
X289336D01*
Y-27048D01*
Y-26994D01*
X289282D01*
Y-26940D01*
Y-26886D01*
X289228D01*
Y-26831D01*
Y-26777D01*
X289174D01*
Y-26723D01*
Y-26669D01*
X289120D01*
Y-26615D01*
Y-26561D01*
Y-26507D01*
X289066D01*
Y-26453D01*
Y-26399D01*
Y-26345D01*
X289012D01*
Y-26291D01*
Y-26237D01*
Y-26183D01*
Y-26129D01*
X288958D01*
Y-26075D01*
Y-26021D01*
Y-25967D01*
Y-25912D01*
Y-25858D01*
X288904D01*
Y-25804D01*
Y-25750D01*
Y-25696D01*
Y-25642D01*
Y-25588D01*
Y-25534D01*
Y-25480D01*
Y-25426D01*
Y-25372D01*
Y-25318D01*
Y-25264D01*
Y-25210D01*
Y-25155D01*
Y-25102D01*
Y-25047D01*
Y-24993D01*
Y-24939D01*
Y-24885D01*
Y-24831D01*
X288958D01*
Y-24777D01*
Y-24723D01*
Y-24669D01*
Y-24615D01*
Y-24561D01*
X289012D01*
Y-24507D01*
Y-24453D01*
Y-24399D01*
Y-24345D01*
X289066D01*
Y-24291D01*
Y-24237D01*
Y-24182D01*
X289120D01*
Y-24128D01*
Y-24074D01*
X289174D01*
Y-24020D01*
Y-23966D01*
Y-23912D01*
X289228D01*
Y-23858D01*
Y-23804D01*
X289282D01*
Y-23750D01*
Y-23696D01*
X289336D01*
Y-23642D01*
Y-23588D01*
X289390D01*
Y-23534D01*
X289444D01*
Y-23480D01*
Y-23426D01*
X289498D01*
Y-23371D01*
X289552D01*
Y-23317D01*
Y-23263D01*
X289606D01*
Y-23209D01*
X289661D01*
Y-23155D01*
X289715D01*
Y-23101D01*
X289769D01*
Y-23047D01*
Y-22993D01*
X289823D01*
Y-22939D01*
X289877D01*
Y-22885D01*
X289931D01*
Y-22831D01*
X289985D01*
Y-22777D01*
X290039D01*
Y-22723D01*
X290147D01*
Y-22669D01*
X290201D01*
Y-22615D01*
X290255D01*
Y-22561D01*
X290309D01*
Y-22506D01*
X290417D01*
Y-22452D01*
X290471D01*
Y-22398D01*
X290580D01*
Y-22344D01*
X290634D01*
Y-22290D01*
X290742D01*
Y-22236D01*
X290850D01*
Y-22182D01*
X290958D01*
Y-22128D01*
X291066D01*
Y-22074D01*
X291228D01*
Y-22020D01*
X291390D01*
Y-21966D01*
X291553D01*
Y-21912D01*
X291769D01*
Y-21858D01*
X292147D01*
Y-21804D01*
X292201D01*
Y-21858D01*
X292255D01*
Y-21804D01*
X335018D01*
Y-21750D01*
X335289D01*
Y-21696D01*
X335505D01*
Y-21642D01*
X335667D01*
Y-21587D01*
X335829D01*
Y-21533D01*
X335938D01*
Y-21479D01*
X336046D01*
Y-21425D01*
X336154D01*
Y-21371D01*
X336262D01*
Y-21317D01*
X336370D01*
Y-21263D01*
X336424D01*
Y-21209D01*
X336532D01*
Y-21155D01*
X336586D01*
Y-21101D01*
X336695D01*
Y-21047D01*
X336749D01*
Y-20993D01*
X336803D01*
Y-20939D01*
X336857D01*
Y-20885D01*
X336911D01*
Y-20831D01*
X336965D01*
Y-20776D01*
X337019D01*
Y-20722D01*
X337073D01*
Y-20668D01*
X337127D01*
Y-20614D01*
X337181D01*
Y-20560D01*
X337235D01*
Y-20506D01*
X337289D01*
Y-20452D01*
X337343D01*
Y-20398D01*
Y-20344D01*
X337397D01*
Y-20290D01*
X337451D01*
Y-20236D01*
Y-20182D01*
X337505D01*
Y-20128D01*
X337560D01*
Y-20074D01*
Y-20020D01*
X337614D01*
Y-19966D01*
Y-19911D01*
X337668D01*
Y-19858D01*
Y-19803D01*
X337722D01*
Y-19749D01*
Y-19695D01*
X337776D01*
Y-19641D01*
Y-19587D01*
X337830D01*
Y-19533D01*
Y-19479D01*
Y-19425D01*
X337884D01*
Y-19371D01*
Y-19317D01*
Y-19263D01*
X337938D01*
Y-19209D01*
Y-19155D01*
Y-19101D01*
Y-19047D01*
X337992D01*
Y-18993D01*
Y-18938D01*
Y-18884D01*
Y-18830D01*
Y-18776D01*
Y-18722D01*
X338046D01*
Y-18668D01*
Y-18614D01*
Y-18560D01*
Y-18506D01*
Y-18452D01*
Y-18398D01*
Y-18344D01*
Y-18290D01*
Y-18236D01*
Y-18181D01*
Y-18127D01*
Y-18073D01*
Y-18019D01*
Y-17965D01*
Y-17911D01*
Y-17857D01*
X337992D01*
Y-17803D01*
Y-17749D01*
Y-17695D01*
Y-17641D01*
Y-17587D01*
Y-17533D01*
X337938D01*
Y-17479D01*
Y-17425D01*
Y-17371D01*
Y-17317D01*
X337884D01*
Y-17263D01*
Y-17208D01*
Y-17154D01*
X337830D01*
Y-17100D01*
Y-17046D01*
X337776D01*
Y-16992D01*
Y-16938D01*
Y-16884D01*
X337722D01*
Y-16830D01*
Y-16776D01*
X337668D01*
Y-16722D01*
Y-16668D01*
X337614D01*
Y-16614D01*
Y-16560D01*
X337560D01*
Y-16506D01*
X337505D01*
Y-16452D01*
Y-16398D01*
X337451D01*
Y-16343D01*
X337397D01*
Y-16289D01*
Y-16235D01*
X337343D01*
Y-16181D01*
X337289D01*
Y-16127D01*
X337235D01*
Y-16073D01*
Y-16019D01*
X337181D01*
Y-15965D01*
X337127D01*
Y-15911D01*
X337073D01*
Y-15857D01*
X337019D01*
Y-15803D01*
X336965D01*
Y-15749D01*
X336911D01*
Y-15695D01*
X336857D01*
Y-15641D01*
X336749D01*
Y-15587D01*
X336695D01*
Y-15532D01*
X336640D01*
Y-15478D01*
X336586D01*
Y-15424D01*
X336478D01*
Y-15370D01*
X336370D01*
Y-15316D01*
X336316D01*
Y-15262D01*
X336208D01*
Y-15208D01*
X336100D01*
Y-15154D01*
X335992D01*
Y-15100D01*
X335883D01*
Y-15046D01*
X335721D01*
Y-14992D01*
X335613D01*
Y-14938D01*
X335397D01*
Y-14884D01*
X335181D01*
Y-14830D01*
X334748D01*
Y-14776D01*
X326585D01*
Y-14722D01*
X326260D01*
Y-14668D01*
X326098D01*
Y-14614D01*
X325882D01*
Y-14559D01*
X325774D01*
Y-14505D01*
X325612D01*
Y-14451D01*
X325504D01*
Y-14397D01*
X325395D01*
Y-14343D01*
X325287D01*
Y-14289D01*
X325233D01*
Y-14235D01*
X325125D01*
Y-14181D01*
X325071D01*
Y-14127D01*
X324963D01*
Y-14073D01*
X324909D01*
Y-14019D01*
X324855D01*
Y-13965D01*
X324747D01*
Y-13911D01*
X324693D01*
Y-13857D01*
X324639D01*
Y-13803D01*
X324585D01*
Y-13748D01*
X324531D01*
Y-13694D01*
X324476D01*
Y-13640D01*
X324422D01*
Y-13586D01*
X324368D01*
Y-13532D01*
X324314D01*
Y-13478D01*
Y-13424D01*
X324260D01*
Y-13370D01*
X324206D01*
Y-13316D01*
X324152D01*
Y-13262D01*
Y-13208D01*
X324098D01*
Y-13154D01*
X324044D01*
Y-13100D01*
Y-13046D01*
X323990D01*
Y-12992D01*
X323936D01*
Y-12937D01*
Y-12883D01*
X323882D01*
Y-12829D01*
Y-12775D01*
X323828D01*
Y-12721D01*
Y-12667D01*
X323774D01*
Y-12613D01*
Y-12559D01*
Y-12505D01*
X323720D01*
Y-12451D01*
Y-12397D01*
Y-12343D01*
X323665D01*
Y-12289D01*
Y-12235D01*
Y-12181D01*
X323611D01*
Y-12127D01*
Y-12072D01*
Y-12019D01*
Y-11964D01*
X323557D01*
Y-11910D01*
Y-11856D01*
Y-11802D01*
Y-11748D01*
Y-11694D01*
Y-11640D01*
Y-11586D01*
X323503D01*
Y-11532D01*
X323557D01*
Y-11478D01*
X323503D01*
Y-11424D01*
Y-11370D01*
Y-11316D01*
Y-11262D01*
Y-11208D01*
Y-11153D01*
Y-11099D01*
Y-11045D01*
Y-10991D01*
Y-10937D01*
Y-10883D01*
X323557D01*
Y-10829D01*
Y-10775D01*
Y-10721D01*
Y-10667D01*
Y-10613D01*
Y-10559D01*
X323611D01*
Y-10505D01*
Y-10451D01*
Y-10397D01*
Y-10343D01*
X323665D01*
Y-10289D01*
Y-10234D01*
Y-10180D01*
X323720D01*
Y-10126D01*
Y-10072D01*
Y-10018D01*
X323774D01*
Y-9964D01*
Y-9910D01*
Y-9856D01*
X323828D01*
Y-9802D01*
Y-9748D01*
X323882D01*
Y-9694D01*
Y-9640D01*
X323936D01*
Y-9586D01*
Y-9532D01*
X323990D01*
Y-9478D01*
X324044D01*
Y-9424D01*
Y-9369D01*
X324098D01*
Y-9315D01*
Y-9261D01*
X324152D01*
Y-9207D01*
X324206D01*
Y-9153D01*
X324260D01*
Y-9099D01*
Y-9045D01*
X324314D01*
Y-8991D01*
X324368D01*
Y-8937D01*
X324422D01*
Y-8883D01*
X324476D01*
Y-8829D01*
X324531D01*
Y-8775D01*
X324585D01*
Y-8721D01*
X324639D01*
Y-8667D01*
X324693D01*
Y-8613D01*
X324747D01*
Y-8558D01*
X324801D01*
Y-8504D01*
X324909D01*
Y-8450D01*
X324963D01*
Y-8396D01*
X325017D01*
Y-8342D01*
X325125D01*
Y-8288D01*
X325179D01*
Y-8234D01*
X325287D01*
Y-8180D01*
X325395D01*
Y-8126D01*
X325504D01*
Y-8072D01*
X325612D01*
Y-8018D01*
X325720D01*
Y-7964D01*
X325882D01*
Y-7910D01*
X326044D01*
Y-7856D01*
X326260D01*
Y-7802D01*
X326477D01*
Y-7748D01*
X327071D01*
Y-7694D01*
X395298D01*
Y-7748D01*
D02*
G37*
G36*
X393514Y-30345D02*
X393730D01*
Y-30400D01*
X393838D01*
Y-30454D01*
X394000D01*
Y-30508D01*
X394108D01*
Y-30562D01*
X394162D01*
Y-30616D01*
X394270D01*
Y-30670D01*
X394325D01*
Y-30724D01*
X394379D01*
Y-30778D01*
X394487D01*
Y-30832D01*
X394541D01*
Y-30886D01*
X394595D01*
Y-30940D01*
X394649D01*
Y-30994D01*
Y-31048D01*
X394703D01*
Y-31102D01*
X394757D01*
Y-31156D01*
X394811D01*
Y-31211D01*
Y-31265D01*
X394865D01*
Y-31319D01*
Y-31373D01*
X394919D01*
Y-31427D01*
Y-31481D01*
X394973D01*
Y-31535D01*
Y-31589D01*
X395027D01*
Y-31643D01*
Y-31697D01*
Y-31751D01*
X395081D01*
Y-31805D01*
Y-31859D01*
Y-31913D01*
Y-31967D01*
Y-32021D01*
X395135D01*
Y-32076D01*
Y-32129D01*
Y-32184D01*
Y-32238D01*
Y-32292D01*
Y-32346D01*
Y-32400D01*
Y-32454D01*
Y-32508D01*
Y-32562D01*
X395081D01*
Y-32616D01*
Y-32670D01*
Y-32724D01*
Y-32778D01*
Y-32832D01*
X395027D01*
Y-32886D01*
Y-32941D01*
Y-32994D01*
X394973D01*
Y-33049D01*
Y-33103D01*
Y-33157D01*
X394919D01*
Y-33211D01*
Y-33265D01*
X394865D01*
Y-33319D01*
X394811D01*
Y-33373D01*
Y-33427D01*
X394757D01*
Y-33481D01*
Y-33535D01*
X394703D01*
Y-33589D01*
X394649D01*
Y-33643D01*
X394595D01*
Y-33697D01*
X394541D01*
Y-33751D01*
X394487D01*
Y-33806D01*
X394433D01*
Y-33860D01*
X394379D01*
Y-33914D01*
X394270D01*
Y-33968D01*
X394216D01*
Y-34022D01*
X394108D01*
Y-34076D01*
X394054D01*
Y-34130D01*
X393892D01*
Y-34184D01*
X393784D01*
Y-34238D01*
X393622D01*
Y-34292D01*
X393297D01*
Y-34346D01*
X392919D01*
Y-34292D01*
X392595D01*
Y-34238D01*
X392432D01*
Y-34184D01*
X392270D01*
Y-34130D01*
X392162D01*
Y-34076D01*
X392054D01*
Y-34022D01*
X392000D01*
Y-33968D01*
X391892D01*
Y-33914D01*
X391838D01*
Y-33860D01*
X391784D01*
Y-33806D01*
X391730D01*
Y-33751D01*
X391675D01*
Y-33697D01*
X391621D01*
Y-33643D01*
X391567D01*
Y-33589D01*
X391513D01*
Y-33535D01*
X391459D01*
Y-33481D01*
Y-33427D01*
X391405D01*
Y-33373D01*
X391351D01*
Y-33319D01*
Y-33265D01*
X391297D01*
Y-33211D01*
Y-33157D01*
X391243D01*
Y-33103D01*
Y-33049D01*
X391189D01*
Y-32994D01*
Y-32941D01*
Y-32886D01*
X391135D01*
Y-32832D01*
Y-32778D01*
Y-32724D01*
Y-32670D01*
X391081D01*
Y-32616D01*
Y-32562D01*
Y-32508D01*
Y-32454D01*
Y-32400D01*
Y-32346D01*
Y-32292D01*
Y-32238D01*
Y-32184D01*
Y-32129D01*
Y-32076D01*
Y-32021D01*
Y-31967D01*
X391135D01*
Y-31913D01*
Y-31859D01*
Y-31805D01*
Y-31751D01*
X391189D01*
Y-31697D01*
Y-31643D01*
Y-31589D01*
X391243D01*
Y-31535D01*
Y-31481D01*
Y-31427D01*
X391297D01*
Y-31373D01*
Y-31319D01*
X391351D01*
Y-31265D01*
X391405D01*
Y-31211D01*
Y-31156D01*
X391459D01*
Y-31102D01*
X391513D01*
Y-31048D01*
Y-30994D01*
X391567D01*
Y-30940D01*
X391621D01*
Y-30886D01*
X391675D01*
Y-30832D01*
X391730D01*
Y-30778D01*
X391784D01*
Y-30724D01*
X391892D01*
Y-30670D01*
X391946D01*
Y-30616D01*
X392054D01*
Y-30562D01*
X392108D01*
Y-30508D01*
X392216D01*
Y-30454D01*
X392324D01*
Y-30400D01*
X392487D01*
Y-30345D01*
X392703D01*
Y-30291D01*
X393514D01*
Y-30345D01*
D02*
G37*
G36*
X393406Y-37644D02*
X393676D01*
Y-37698D01*
X393838D01*
Y-37752D01*
X393946D01*
Y-37806D01*
X394054D01*
Y-37860D01*
X394162D01*
Y-37914D01*
X394216D01*
Y-37968D01*
X394325D01*
Y-38022D01*
X394379D01*
Y-38076D01*
X394433D01*
Y-38130D01*
X394487D01*
Y-38184D01*
X394541D01*
Y-38238D01*
X394595D01*
Y-38293D01*
X394649D01*
Y-38347D01*
X394703D01*
Y-38401D01*
X394757D01*
Y-38455D01*
Y-38509D01*
X394811D01*
Y-38563D01*
X394865D01*
Y-38617D01*
Y-38671D01*
X394919D01*
Y-38725D01*
Y-38779D01*
X394973D01*
Y-38833D01*
Y-38887D01*
X395027D01*
Y-38941D01*
Y-38995D01*
Y-39050D01*
Y-39103D01*
X395081D01*
Y-39158D01*
Y-39212D01*
Y-39266D01*
Y-39320D01*
X395135D01*
Y-39374D01*
Y-39428D01*
Y-39482D01*
Y-39536D01*
Y-39590D01*
Y-39644D01*
Y-39698D01*
Y-39752D01*
Y-39806D01*
Y-39860D01*
Y-39915D01*
X395081D01*
Y-39968D01*
Y-40023D01*
Y-40077D01*
Y-40131D01*
X395027D01*
Y-40185D01*
Y-40239D01*
Y-40293D01*
X394973D01*
Y-40347D01*
Y-40401D01*
Y-40455D01*
X394919D01*
Y-40509D01*
Y-40563D01*
X394865D01*
Y-40617D01*
Y-40671D01*
X394811D01*
Y-40725D01*
X394757D01*
Y-40780D01*
Y-40834D01*
X394703D01*
Y-40888D01*
X394649D01*
Y-40942D01*
X394595D01*
Y-40996D01*
X394541D01*
Y-41050D01*
X394487D01*
Y-41104D01*
X394433D01*
Y-41158D01*
X394379D01*
Y-41212D01*
X394325D01*
Y-41266D01*
X394216D01*
Y-41320D01*
X394162D01*
Y-41374D01*
X394054D01*
Y-41428D01*
X393946D01*
Y-41482D01*
X393838D01*
Y-41536D01*
X393676D01*
Y-41590D01*
X393406D01*
Y-41644D01*
X392811D01*
Y-41590D01*
X392541D01*
Y-41536D01*
X392378D01*
Y-41482D01*
X392270D01*
Y-41428D01*
X392162D01*
Y-41374D01*
X392054D01*
Y-41320D01*
X391946D01*
Y-41266D01*
X391892D01*
Y-41212D01*
X391838D01*
Y-41158D01*
X391784D01*
Y-41104D01*
X391675D01*
Y-41050D01*
X391621D01*
Y-40996D01*
X391567D01*
Y-40942D01*
Y-40888D01*
X391513D01*
Y-40834D01*
X391459D01*
Y-40780D01*
X391405D01*
Y-40725D01*
Y-40671D01*
X391351D01*
Y-40617D01*
Y-40563D01*
X391297D01*
Y-40509D01*
Y-40455D01*
X391243D01*
Y-40401D01*
Y-40347D01*
X391189D01*
Y-40293D01*
Y-40239D01*
Y-40185D01*
X391135D01*
Y-40131D01*
Y-40077D01*
Y-40023D01*
Y-39968D01*
X391081D01*
Y-39915D01*
Y-39860D01*
Y-39806D01*
Y-39752D01*
Y-39698D01*
Y-39644D01*
Y-39590D01*
Y-39536D01*
Y-39482D01*
Y-39428D01*
Y-39374D01*
Y-39320D01*
Y-39266D01*
X391135D01*
Y-39212D01*
Y-39158D01*
Y-39103D01*
Y-39050D01*
X391189D01*
Y-38995D01*
Y-38941D01*
Y-38887D01*
X391243D01*
Y-38833D01*
Y-38779D01*
X391297D01*
Y-38725D01*
Y-38671D01*
X391351D01*
Y-38617D01*
Y-38563D01*
X391405D01*
Y-38509D01*
Y-38455D01*
X391459D01*
Y-38401D01*
X391513D01*
Y-38347D01*
X391567D01*
Y-38293D01*
Y-38238D01*
X391621D01*
Y-38184D01*
X391675D01*
Y-38130D01*
X391730D01*
Y-38076D01*
X391838D01*
Y-38022D01*
X391892D01*
Y-37968D01*
X391946D01*
Y-37914D01*
X392054D01*
Y-37860D01*
X392162D01*
Y-37806D01*
X392270D01*
Y-37752D01*
X392378D01*
Y-37698D01*
X392541D01*
Y-37644D01*
X392757D01*
Y-37590D01*
X393406D01*
Y-37644D01*
D02*
G37*
G36*
X299338Y-35968D02*
X299608D01*
Y-36022D01*
X299824D01*
Y-36076D01*
X299986D01*
Y-36130D01*
X300149D01*
Y-36184D01*
X300311D01*
Y-36238D01*
X300419D01*
Y-36292D01*
X300527D01*
Y-36346D01*
X300635D01*
Y-36400D01*
X300689D01*
Y-36454D01*
X300797D01*
Y-36509D01*
X300851D01*
Y-36563D01*
X300959D01*
Y-36617D01*
X301013D01*
Y-36671D01*
X301122D01*
Y-36725D01*
X301176D01*
Y-36779D01*
X301230D01*
Y-36833D01*
X301284D01*
Y-36887D01*
X301338D01*
Y-36941D01*
X301392D01*
Y-36995D01*
X301446D01*
Y-37049D01*
X301500D01*
Y-37103D01*
X301554D01*
Y-37157D01*
X301608D01*
Y-37211D01*
X301662D01*
Y-37265D01*
Y-37319D01*
X301716D01*
Y-37374D01*
X301770D01*
Y-37428D01*
X301824D01*
Y-37482D01*
Y-37536D01*
X301878D01*
Y-37590D01*
X301933D01*
Y-37644D01*
Y-37698D01*
X301987D01*
Y-37752D01*
Y-37806D01*
X302041D01*
Y-37860D01*
Y-37914D01*
X302095D01*
Y-37968D01*
Y-38022D01*
X302149D01*
Y-38076D01*
Y-38130D01*
X302203D01*
Y-38184D01*
Y-38238D01*
Y-38293D01*
X302257D01*
Y-38347D01*
Y-38401D01*
Y-38455D01*
X302311D01*
Y-38509D01*
Y-38563D01*
Y-38617D01*
Y-38671D01*
X302365D01*
Y-38725D01*
Y-38779D01*
Y-38833D01*
Y-38887D01*
Y-38941D01*
X302419D01*
Y-38995D01*
Y-39050D01*
Y-39103D01*
Y-39158D01*
Y-39212D01*
Y-39266D01*
Y-39320D01*
Y-39374D01*
Y-39428D01*
Y-39482D01*
Y-39536D01*
Y-39590D01*
Y-39644D01*
Y-39698D01*
Y-39752D01*
Y-39806D01*
Y-39860D01*
Y-39915D01*
Y-39968D01*
X302365D01*
Y-40023D01*
Y-40077D01*
Y-40131D01*
Y-40185D01*
Y-40239D01*
X302311D01*
Y-40293D01*
Y-40347D01*
Y-40401D01*
Y-40455D01*
X302257D01*
Y-40509D01*
Y-40563D01*
Y-40617D01*
X302203D01*
Y-40671D01*
Y-40725D01*
X302149D01*
Y-40780D01*
Y-40834D01*
Y-40888D01*
X302095D01*
Y-40942D01*
Y-40996D01*
X302041D01*
Y-41050D01*
Y-41104D01*
X301987D01*
Y-41158D01*
X301933D01*
Y-41212D01*
Y-41266D01*
X301878D01*
Y-41320D01*
Y-41374D01*
X301824D01*
Y-41428D01*
X301770D01*
Y-41482D01*
Y-41536D01*
X301716D01*
Y-41590D01*
X301662D01*
Y-41644D01*
X301608D01*
Y-41699D01*
X301554D01*
Y-41753D01*
Y-41807D01*
X301500D01*
Y-41861D01*
X301446D01*
Y-41915D01*
X301392D01*
Y-41969D01*
X301338D01*
Y-42023D01*
X301284D01*
Y-42077D01*
X301176D01*
Y-42131D01*
X301122D01*
Y-42185D01*
X301068D01*
Y-42239D01*
X301013D01*
Y-42293D01*
X300905D01*
Y-42347D01*
X300851D01*
Y-42401D01*
X300743D01*
Y-42455D01*
X300689D01*
Y-42509D01*
X300581D01*
Y-42564D01*
X300473D01*
Y-42618D01*
X300365D01*
Y-42672D01*
X300257D01*
Y-42726D01*
X300095D01*
Y-42780D01*
X299932D01*
Y-42834D01*
X299770D01*
Y-42888D01*
X299500D01*
Y-42942D01*
X299121D01*
Y-42996D01*
X298743D01*
Y-42942D01*
X298689D01*
Y-42996D01*
X298635D01*
Y-42942D01*
X298581D01*
Y-42996D01*
X298527D01*
Y-42942D01*
X298202D01*
Y-42888D01*
X297932D01*
Y-42834D01*
X297716D01*
Y-42780D01*
X297554D01*
Y-42726D01*
X297445D01*
Y-42672D01*
X297283D01*
Y-42618D01*
X297175D01*
Y-42564D01*
X297067D01*
Y-42509D01*
X297013D01*
Y-42455D01*
X296905D01*
Y-42401D01*
X296797D01*
Y-42347D01*
X296743D01*
Y-42293D01*
X296689D01*
Y-42239D01*
X296581D01*
Y-42185D01*
X296526D01*
Y-42131D01*
X296472D01*
Y-42077D01*
X296418D01*
Y-42023D01*
X296364D01*
Y-41969D01*
X296310D01*
Y-41915D01*
X296256D01*
Y-41861D01*
X296202D01*
Y-41807D01*
X296148D01*
Y-41753D01*
X296094D01*
Y-41699D01*
X296040D01*
Y-41644D01*
X295986D01*
Y-41590D01*
X295932D01*
Y-41536D01*
Y-41482D01*
X295878D01*
Y-41428D01*
X295824D01*
Y-41374D01*
Y-41320D01*
X295770D01*
Y-41266D01*
X295715D01*
Y-41212D01*
Y-41158D01*
X295661D01*
Y-41104D01*
Y-41050D01*
X295607D01*
Y-40996D01*
Y-40942D01*
X295553D01*
Y-40888D01*
Y-40834D01*
X295499D01*
Y-40780D01*
Y-40725D01*
X295445D01*
Y-40671D01*
Y-40617D01*
Y-40563D01*
X295391D01*
Y-40509D01*
Y-40455D01*
Y-40401D01*
X295337D01*
Y-40347D01*
Y-40293D01*
Y-40239D01*
Y-40185D01*
X295283D01*
Y-40131D01*
Y-40077D01*
Y-40023D01*
Y-39968D01*
Y-39915D01*
Y-39860D01*
X295229D01*
Y-39806D01*
Y-39752D01*
Y-39698D01*
Y-39644D01*
Y-39590D01*
Y-39536D01*
Y-39482D01*
Y-39428D01*
Y-39374D01*
Y-39320D01*
Y-39266D01*
Y-39212D01*
Y-39158D01*
Y-39103D01*
Y-39050D01*
X295283D01*
Y-38995D01*
Y-38941D01*
Y-38887D01*
Y-38833D01*
Y-38779D01*
Y-38725D01*
X295337D01*
Y-38671D01*
Y-38617D01*
Y-38563D01*
Y-38509D01*
X295391D01*
Y-38455D01*
Y-38401D01*
Y-38347D01*
X295445D01*
Y-38293D01*
Y-38238D01*
Y-38184D01*
X295499D01*
Y-38130D01*
Y-38076D01*
X295553D01*
Y-38022D01*
Y-37968D01*
Y-37914D01*
X295607D01*
Y-37860D01*
Y-37806D01*
X295661D01*
Y-37752D01*
X295715D01*
Y-37698D01*
Y-37644D01*
X295770D01*
Y-37590D01*
Y-37536D01*
X295824D01*
Y-37482D01*
X295878D01*
Y-37428D01*
Y-37374D01*
X295932D01*
Y-37319D01*
X295986D01*
Y-37265D01*
X296040D01*
Y-37211D01*
Y-37157D01*
X296094D01*
Y-37103D01*
X296148D01*
Y-37049D01*
X296202D01*
Y-36995D01*
X296256D01*
Y-36941D01*
X296310D01*
Y-36887D01*
X296364D01*
Y-36833D01*
X296418D01*
Y-36779D01*
X296526D01*
Y-36725D01*
X296581D01*
Y-36671D01*
X296635D01*
Y-36617D01*
X296689D01*
Y-36563D01*
X296797D01*
Y-36509D01*
X296851D01*
Y-36454D01*
X296959D01*
Y-36400D01*
X297067D01*
Y-36346D01*
X297121D01*
Y-36292D01*
X297229D01*
Y-36238D01*
X297391D01*
Y-36184D01*
X297499D01*
Y-36130D01*
X297662D01*
Y-36076D01*
X297824D01*
Y-36022D01*
X298040D01*
Y-35968D01*
X298364D01*
Y-35914D01*
X299338D01*
Y-35968D01*
D02*
G37*
G36*
X393352Y-44942D02*
X393622D01*
Y-44996D01*
X393784D01*
Y-45050D01*
X393946D01*
Y-45104D01*
X394054D01*
Y-45158D01*
X394108D01*
Y-45213D01*
X394216D01*
Y-45267D01*
X394325D01*
Y-45321D01*
X394379D01*
Y-45375D01*
X394433D01*
Y-45429D01*
X394487D01*
Y-45483D01*
X394541D01*
Y-45537D01*
X394595D01*
Y-45591D01*
X394649D01*
Y-45645D01*
X394703D01*
Y-45699D01*
X394757D01*
Y-45753D01*
Y-45807D01*
X394811D01*
Y-45861D01*
X394865D01*
Y-45915D01*
Y-45969D01*
X394919D01*
Y-46023D01*
Y-46077D01*
X394973D01*
Y-46132D01*
Y-46186D01*
Y-46240D01*
X395027D01*
Y-46294D01*
Y-46348D01*
Y-46402D01*
X395081D01*
Y-46456D01*
Y-46510D01*
Y-46564D01*
Y-46618D01*
Y-46672D01*
X395135D01*
Y-46726D01*
Y-46780D01*
Y-46834D01*
Y-46889D01*
Y-46942D01*
Y-46997D01*
Y-47051D01*
Y-47105D01*
Y-47159D01*
Y-47213D01*
X395081D01*
Y-47267D01*
Y-47321D01*
Y-47375D01*
Y-47429D01*
Y-47483D01*
X395027D01*
Y-47537D01*
Y-47591D01*
Y-47645D01*
X394973D01*
Y-47699D01*
Y-47754D01*
X394919D01*
Y-47807D01*
Y-47862D01*
X394865D01*
Y-47916D01*
Y-47970D01*
X394811D01*
Y-48024D01*
Y-48078D01*
X394757D01*
Y-48132D01*
X394703D01*
Y-48186D01*
X394649D01*
Y-48240D01*
Y-48294D01*
X394595D01*
Y-48348D01*
X394541D01*
Y-48402D01*
X394487D01*
Y-48456D01*
X394379D01*
Y-48510D01*
X394325D01*
Y-48564D01*
X394270D01*
Y-48619D01*
X394162D01*
Y-48673D01*
X394054D01*
Y-48727D01*
X394000D01*
Y-48781D01*
X393838D01*
Y-48835D01*
X393676D01*
Y-48889D01*
X393514D01*
Y-48943D01*
X392703D01*
Y-48889D01*
X392487D01*
Y-48835D01*
X392378D01*
Y-48781D01*
X392216D01*
Y-48727D01*
X392108D01*
Y-48673D01*
X392054D01*
Y-48619D01*
X391946D01*
Y-48564D01*
X391892D01*
Y-48510D01*
X391784D01*
Y-48456D01*
X391730D01*
Y-48402D01*
X391675D01*
Y-48348D01*
X391621D01*
Y-48294D01*
X391567D01*
Y-48240D01*
X391513D01*
Y-48186D01*
Y-48132D01*
X391459D01*
Y-48078D01*
X391405D01*
Y-48024D01*
Y-47970D01*
X391351D01*
Y-47916D01*
X391297D01*
Y-47862D01*
Y-47807D01*
X391243D01*
Y-47754D01*
Y-47699D01*
Y-47645D01*
X391189D01*
Y-47591D01*
Y-47537D01*
Y-47483D01*
X391135D01*
Y-47429D01*
Y-47375D01*
Y-47321D01*
Y-47267D01*
X391081D01*
Y-47213D01*
Y-47159D01*
Y-47105D01*
Y-47051D01*
Y-46997D01*
Y-46942D01*
Y-46889D01*
Y-46834D01*
Y-46780D01*
Y-46726D01*
Y-46672D01*
Y-46618D01*
Y-46564D01*
X391135D01*
Y-46510D01*
Y-46456D01*
Y-46402D01*
Y-46348D01*
X391189D01*
Y-46294D01*
Y-46240D01*
Y-46186D01*
X391243D01*
Y-46132D01*
Y-46077D01*
X391297D01*
Y-46023D01*
Y-45969D01*
X391351D01*
Y-45915D01*
Y-45861D01*
X391405D01*
Y-45807D01*
X391459D01*
Y-45753D01*
Y-45699D01*
X391513D01*
Y-45645D01*
X391567D01*
Y-45591D01*
X391621D01*
Y-45537D01*
X391675D01*
Y-45483D01*
X391730D01*
Y-45429D01*
X391784D01*
Y-45375D01*
X391838D01*
Y-45321D01*
X391892D01*
Y-45267D01*
X392000D01*
Y-45213D01*
X392054D01*
Y-45158D01*
X392162D01*
Y-45104D01*
X392270D01*
Y-45050D01*
X392432D01*
Y-44996D01*
X392595D01*
Y-44942D01*
X392865D01*
Y-44888D01*
X393352D01*
Y-44942D01*
D02*
G37*
G36*
X393568Y-52295D02*
X393730D01*
Y-52349D01*
X393892D01*
Y-52403D01*
X394000D01*
Y-52457D01*
X394108D01*
Y-52511D01*
X394216D01*
Y-52565D01*
X394270D01*
Y-52619D01*
X394379D01*
Y-52673D01*
X394433D01*
Y-52727D01*
X394487D01*
Y-52781D01*
X394541D01*
Y-52835D01*
X394595D01*
Y-52889D01*
X394649D01*
Y-52943D01*
X394703D01*
Y-52997D01*
Y-53052D01*
X394757D01*
Y-53106D01*
X394811D01*
Y-53160D01*
Y-53214D01*
X394865D01*
Y-53268D01*
Y-53322D01*
X394919D01*
Y-53376D01*
Y-53430D01*
X394973D01*
Y-53484D01*
Y-53538D01*
X395027D01*
Y-53592D01*
Y-53646D01*
Y-53700D01*
X395081D01*
Y-53754D01*
Y-53808D01*
Y-53863D01*
Y-53917D01*
Y-53971D01*
X395135D01*
Y-54025D01*
Y-54079D01*
Y-54133D01*
Y-54187D01*
Y-54241D01*
Y-54295D01*
Y-54349D01*
Y-54403D01*
Y-54457D01*
Y-54511D01*
X395081D01*
Y-54565D01*
Y-54619D01*
Y-54673D01*
Y-54728D01*
Y-54782D01*
X395027D01*
Y-54836D01*
Y-54890D01*
Y-54944D01*
X394973D01*
Y-54998D01*
Y-55052D01*
X394919D01*
Y-55106D01*
Y-55160D01*
X394865D01*
Y-55214D01*
Y-55268D01*
X394811D01*
Y-55322D01*
Y-55376D01*
X394757D01*
Y-55430D01*
X394703D01*
Y-55484D01*
Y-55538D01*
X394649D01*
Y-55592D01*
X394595D01*
Y-55647D01*
X394541D01*
Y-55701D01*
X394487D01*
Y-55755D01*
X394433D01*
Y-55809D01*
X394325D01*
Y-55863D01*
X394270D01*
Y-55917D01*
X394216D01*
Y-55971D01*
X394108D01*
Y-56025D01*
X394000D01*
Y-56079D01*
X393892D01*
Y-56133D01*
X393730D01*
Y-56187D01*
X393568D01*
Y-56241D01*
X392649D01*
Y-56187D01*
X392487D01*
Y-56133D01*
X392324D01*
Y-56079D01*
X392216D01*
Y-56025D01*
X392108D01*
Y-55971D01*
X392000D01*
Y-55917D01*
X391946D01*
Y-55863D01*
X391838D01*
Y-55809D01*
X391784D01*
Y-55755D01*
X391730D01*
Y-55701D01*
X391675D01*
Y-55647D01*
X391621D01*
Y-55592D01*
X391567D01*
Y-55538D01*
X391513D01*
Y-55484D01*
X391459D01*
Y-55430D01*
Y-55376D01*
X391405D01*
Y-55322D01*
X391351D01*
Y-55268D01*
Y-55214D01*
X391297D01*
Y-55160D01*
Y-55106D01*
X391243D01*
Y-55052D01*
Y-54998D01*
X391189D01*
Y-54944D01*
Y-54890D01*
Y-54836D01*
X391135D01*
Y-54782D01*
Y-54728D01*
Y-54673D01*
Y-54619D01*
Y-54565D01*
X391081D01*
Y-54511D01*
Y-54457D01*
Y-54403D01*
Y-54349D01*
Y-54295D01*
Y-54241D01*
Y-54187D01*
Y-54133D01*
Y-54079D01*
Y-54025D01*
Y-53971D01*
Y-53917D01*
X391135D01*
Y-53863D01*
Y-53808D01*
Y-53754D01*
Y-53700D01*
Y-53646D01*
X391189D01*
Y-53592D01*
Y-53538D01*
Y-53484D01*
X391243D01*
Y-53430D01*
Y-53376D01*
X391297D01*
Y-53322D01*
Y-53268D01*
X391351D01*
Y-53214D01*
Y-53160D01*
X391405D01*
Y-53106D01*
X391459D01*
Y-53052D01*
Y-52997D01*
X391513D01*
Y-52943D01*
X391567D01*
Y-52889D01*
X391621D01*
Y-52835D01*
X391675D01*
Y-52781D01*
X391730D01*
Y-52727D01*
X391784D01*
Y-52673D01*
X391838D01*
Y-52619D01*
X391946D01*
Y-52565D01*
X392000D01*
Y-52511D01*
X392108D01*
Y-52457D01*
X392216D01*
Y-52403D01*
X392324D01*
Y-52349D01*
X392432D01*
Y-52295D01*
X392649D01*
Y-52241D01*
X393568D01*
Y-52295D01*
D02*
G37*
G36*
X407408Y-7748D02*
Y-7802D01*
Y-7856D01*
Y-7910D01*
Y-7964D01*
Y-8018D01*
Y-8072D01*
Y-8126D01*
Y-8180D01*
Y-8234D01*
Y-8288D01*
Y-8342D01*
Y-8396D01*
Y-8450D01*
Y-8504D01*
Y-8558D01*
Y-8613D01*
Y-8667D01*
Y-8721D01*
Y-8775D01*
Y-8829D01*
Y-8883D01*
Y-8937D01*
Y-8991D01*
Y-9045D01*
Y-9099D01*
Y-9153D01*
Y-9207D01*
Y-9261D01*
Y-9315D01*
Y-9369D01*
Y-9424D01*
Y-9478D01*
Y-9532D01*
Y-9586D01*
Y-9640D01*
Y-9694D01*
Y-9748D01*
X400542D01*
Y-9802D01*
X400325D01*
Y-9856D01*
X400217D01*
Y-9910D01*
X400109D01*
Y-9964D01*
X400001D01*
Y-10018D01*
X399947D01*
Y-10072D01*
X399839D01*
Y-10126D01*
X399785D01*
Y-10180D01*
X399731D01*
Y-10234D01*
X399677D01*
Y-10289D01*
Y-10343D01*
X399623D01*
Y-10397D01*
X399569D01*
Y-10451D01*
Y-10505D01*
X399515D01*
Y-10559D01*
Y-10613D01*
X399460D01*
Y-10667D01*
Y-10721D01*
X399406D01*
Y-10775D01*
Y-10829D01*
Y-10883D01*
Y-10937D01*
Y-10991D01*
X399352D01*
Y-11045D01*
Y-11099D01*
Y-11153D01*
Y-11208D01*
Y-11262D01*
Y-11316D01*
Y-11370D01*
Y-11424D01*
Y-11478D01*
Y-11532D01*
Y-11586D01*
Y-11640D01*
Y-11694D01*
Y-11748D01*
Y-11802D01*
Y-11856D01*
Y-11910D01*
Y-11964D01*
Y-12019D01*
Y-12072D01*
Y-12127D01*
Y-12181D01*
Y-12235D01*
Y-12289D01*
Y-12343D01*
Y-12397D01*
Y-12451D01*
Y-12505D01*
Y-12559D01*
Y-12613D01*
Y-12667D01*
Y-12721D01*
Y-12775D01*
Y-12829D01*
Y-12883D01*
Y-12937D01*
Y-12992D01*
Y-13046D01*
Y-13100D01*
Y-13154D01*
Y-13208D01*
Y-13262D01*
Y-13316D01*
Y-13370D01*
Y-13424D01*
Y-13478D01*
Y-13532D01*
Y-13586D01*
Y-13640D01*
Y-13694D01*
Y-13748D01*
Y-13803D01*
Y-13857D01*
Y-13911D01*
Y-13965D01*
Y-14019D01*
Y-14073D01*
Y-14127D01*
Y-14181D01*
Y-14235D01*
Y-14289D01*
Y-14343D01*
Y-14397D01*
Y-14451D01*
Y-14505D01*
Y-14559D01*
Y-14614D01*
Y-14668D01*
Y-14722D01*
Y-14776D01*
Y-14830D01*
Y-14884D01*
Y-14938D01*
Y-14992D01*
Y-15046D01*
Y-15100D01*
Y-15154D01*
Y-15208D01*
Y-15262D01*
Y-15316D01*
Y-15370D01*
Y-15424D01*
Y-15478D01*
Y-15532D01*
Y-15587D01*
Y-15641D01*
Y-15695D01*
Y-15749D01*
Y-15803D01*
Y-15857D01*
Y-15911D01*
Y-15965D01*
Y-16019D01*
Y-16073D01*
Y-16127D01*
Y-16181D01*
Y-16235D01*
Y-16289D01*
Y-16343D01*
Y-16398D01*
Y-16452D01*
Y-16506D01*
Y-16560D01*
Y-16614D01*
Y-16668D01*
Y-16722D01*
Y-16776D01*
Y-16830D01*
Y-16884D01*
Y-16938D01*
Y-16992D01*
Y-17046D01*
Y-17100D01*
Y-17154D01*
Y-17208D01*
Y-17263D01*
Y-17317D01*
Y-17371D01*
Y-17425D01*
Y-17479D01*
Y-17533D01*
Y-17587D01*
Y-17641D01*
Y-17695D01*
Y-17749D01*
Y-17803D01*
Y-17857D01*
Y-17911D01*
Y-17965D01*
Y-18019D01*
Y-18073D01*
Y-18127D01*
Y-18181D01*
Y-18236D01*
Y-18290D01*
Y-18344D01*
Y-18398D01*
Y-18452D01*
Y-18506D01*
Y-18560D01*
Y-18614D01*
Y-18668D01*
Y-18722D01*
Y-18776D01*
Y-18830D01*
Y-18884D01*
Y-18938D01*
Y-18993D01*
Y-19047D01*
Y-19101D01*
Y-19155D01*
Y-19209D01*
Y-19263D01*
Y-19317D01*
Y-19371D01*
Y-19425D01*
Y-19479D01*
Y-19533D01*
Y-19587D01*
Y-19641D01*
Y-19695D01*
Y-19749D01*
Y-19803D01*
Y-19858D01*
Y-19911D01*
Y-19966D01*
Y-20020D01*
Y-20074D01*
Y-20128D01*
Y-20182D01*
Y-20236D01*
Y-20290D01*
Y-20344D01*
Y-20398D01*
Y-20452D01*
Y-20506D01*
Y-20560D01*
Y-20614D01*
Y-20668D01*
Y-20722D01*
Y-20776D01*
Y-20831D01*
Y-20885D01*
Y-20939D01*
Y-20993D01*
Y-21047D01*
Y-21101D01*
Y-21155D01*
Y-21209D01*
Y-21263D01*
Y-21317D01*
Y-21371D01*
Y-21425D01*
Y-21479D01*
Y-21533D01*
Y-21587D01*
Y-21642D01*
Y-21696D01*
Y-21750D01*
Y-21804D01*
Y-21858D01*
Y-21912D01*
Y-21966D01*
Y-22020D01*
Y-22074D01*
Y-22128D01*
Y-22182D01*
Y-22236D01*
Y-22290D01*
Y-22344D01*
Y-22398D01*
Y-22452D01*
Y-22506D01*
Y-22561D01*
Y-22615D01*
Y-22669D01*
Y-22723D01*
Y-22777D01*
Y-22831D01*
Y-22885D01*
Y-22939D01*
Y-22993D01*
Y-23047D01*
Y-23101D01*
Y-23155D01*
Y-23209D01*
Y-23263D01*
Y-23317D01*
Y-23371D01*
Y-23426D01*
Y-23480D01*
Y-23534D01*
Y-23588D01*
Y-23642D01*
Y-23696D01*
Y-23750D01*
Y-23804D01*
Y-23858D01*
Y-23912D01*
Y-23966D01*
Y-24020D01*
Y-24074D01*
Y-24128D01*
Y-24182D01*
Y-24237D01*
Y-24291D01*
Y-24345D01*
Y-24399D01*
Y-24453D01*
Y-24507D01*
Y-24561D01*
Y-24615D01*
Y-24669D01*
Y-24723D01*
Y-24777D01*
Y-24831D01*
Y-24885D01*
Y-24939D01*
Y-24993D01*
Y-25047D01*
Y-25102D01*
Y-25155D01*
Y-25210D01*
Y-25264D01*
Y-25318D01*
Y-25372D01*
Y-25426D01*
Y-25480D01*
Y-25534D01*
Y-25588D01*
Y-25642D01*
Y-25696D01*
Y-25750D01*
Y-25804D01*
Y-25858D01*
Y-25912D01*
Y-25967D01*
Y-26021D01*
Y-26075D01*
Y-26129D01*
Y-26183D01*
Y-26237D01*
Y-26291D01*
Y-26345D01*
Y-26399D01*
Y-26453D01*
Y-26507D01*
Y-26561D01*
Y-26615D01*
Y-26669D01*
Y-26723D01*
Y-26777D01*
Y-26831D01*
Y-26886D01*
Y-26940D01*
Y-26994D01*
Y-27048D01*
Y-27102D01*
Y-27156D01*
Y-27210D01*
Y-27264D01*
Y-27318D01*
Y-27372D01*
Y-27426D01*
Y-27480D01*
Y-27534D01*
Y-27588D01*
Y-27642D01*
Y-27696D01*
Y-27751D01*
Y-27805D01*
Y-27859D01*
Y-27913D01*
Y-27967D01*
Y-28021D01*
Y-28075D01*
Y-28129D01*
Y-28183D01*
Y-28237D01*
Y-28291D01*
Y-28345D01*
Y-28399D01*
Y-28453D01*
Y-28507D01*
Y-28561D01*
Y-28615D01*
Y-28670D01*
Y-28724D01*
Y-28778D01*
Y-28832D01*
Y-28886D01*
Y-28940D01*
Y-28994D01*
Y-29048D01*
Y-29102D01*
Y-29156D01*
Y-29210D01*
Y-29264D01*
Y-29318D01*
Y-29372D01*
Y-29426D01*
Y-29480D01*
Y-29535D01*
Y-29589D01*
Y-29643D01*
Y-29697D01*
Y-29751D01*
Y-29805D01*
Y-29859D01*
Y-29913D01*
Y-29967D01*
Y-30021D01*
Y-30075D01*
Y-30129D01*
Y-30183D01*
Y-30237D01*
Y-30291D01*
Y-30345D01*
Y-30400D01*
Y-30454D01*
Y-30508D01*
Y-30562D01*
Y-30616D01*
Y-30670D01*
Y-30724D01*
Y-30778D01*
Y-30832D01*
Y-30886D01*
Y-30940D01*
Y-30994D01*
Y-31048D01*
Y-31102D01*
Y-31156D01*
Y-31211D01*
Y-31265D01*
Y-31319D01*
Y-31373D01*
Y-31427D01*
Y-31481D01*
Y-31535D01*
Y-31589D01*
Y-31643D01*
Y-31697D01*
Y-31751D01*
Y-31805D01*
Y-31859D01*
Y-31913D01*
Y-31967D01*
Y-32021D01*
Y-32076D01*
Y-32129D01*
Y-32184D01*
Y-32238D01*
Y-32292D01*
Y-32346D01*
Y-32400D01*
Y-32454D01*
Y-32508D01*
Y-32562D01*
Y-32616D01*
Y-32670D01*
Y-32724D01*
Y-32778D01*
Y-32832D01*
Y-32886D01*
Y-32941D01*
Y-32994D01*
Y-33049D01*
Y-33103D01*
Y-33157D01*
Y-33211D01*
Y-33265D01*
Y-33319D01*
Y-33373D01*
Y-33427D01*
Y-33481D01*
Y-33535D01*
Y-33589D01*
Y-33643D01*
Y-33697D01*
Y-33751D01*
Y-33806D01*
Y-33860D01*
Y-33914D01*
Y-33968D01*
Y-34022D01*
Y-34076D01*
Y-34130D01*
Y-34184D01*
Y-34238D01*
Y-34292D01*
Y-34346D01*
Y-34400D01*
Y-34454D01*
Y-34508D01*
Y-34562D01*
Y-34616D01*
Y-34670D01*
Y-34725D01*
Y-34779D01*
Y-34833D01*
Y-34887D01*
Y-34941D01*
Y-34995D01*
Y-35049D01*
Y-35103D01*
Y-35157D01*
Y-35211D01*
Y-35265D01*
Y-35319D01*
Y-35373D01*
Y-35427D01*
Y-35481D01*
Y-35535D01*
Y-35590D01*
Y-35644D01*
Y-35698D01*
Y-35752D01*
Y-35806D01*
Y-35860D01*
Y-35914D01*
Y-35968D01*
Y-36022D01*
Y-36076D01*
Y-36130D01*
Y-36184D01*
Y-36238D01*
Y-36292D01*
Y-36346D01*
Y-36400D01*
Y-36454D01*
Y-36509D01*
Y-36563D01*
Y-36617D01*
Y-36671D01*
Y-36725D01*
Y-36779D01*
Y-36833D01*
Y-36887D01*
Y-36941D01*
Y-36995D01*
Y-37049D01*
Y-37103D01*
Y-37157D01*
Y-37211D01*
Y-37265D01*
Y-37319D01*
Y-37374D01*
Y-37428D01*
Y-37482D01*
Y-37536D01*
Y-37590D01*
Y-37644D01*
Y-37698D01*
Y-37752D01*
Y-37806D01*
Y-37860D01*
Y-37914D01*
Y-37968D01*
Y-38022D01*
Y-38076D01*
Y-38130D01*
Y-38184D01*
Y-38238D01*
Y-38293D01*
Y-38347D01*
Y-38401D01*
Y-38455D01*
Y-38509D01*
Y-38563D01*
Y-38617D01*
Y-38671D01*
Y-38725D01*
Y-38779D01*
Y-38833D01*
Y-38887D01*
Y-38941D01*
Y-38995D01*
Y-39050D01*
Y-39103D01*
Y-39158D01*
Y-39212D01*
Y-39266D01*
Y-39320D01*
Y-39374D01*
Y-39428D01*
Y-39482D01*
Y-39536D01*
Y-39590D01*
Y-39644D01*
Y-39698D01*
Y-39752D01*
Y-39806D01*
Y-39860D01*
Y-39915D01*
Y-39968D01*
Y-40023D01*
Y-40077D01*
Y-40131D01*
Y-40185D01*
Y-40239D01*
Y-40293D01*
Y-40347D01*
Y-40401D01*
Y-40455D01*
Y-40509D01*
Y-40563D01*
Y-40617D01*
Y-40671D01*
Y-40725D01*
Y-40780D01*
Y-40834D01*
Y-40888D01*
Y-40942D01*
Y-40996D01*
Y-41050D01*
Y-41104D01*
Y-41158D01*
Y-41212D01*
Y-41266D01*
Y-41320D01*
Y-41374D01*
Y-41428D01*
Y-41482D01*
Y-41536D01*
Y-41590D01*
Y-41644D01*
Y-41699D01*
Y-41753D01*
Y-41807D01*
Y-41861D01*
Y-41915D01*
Y-41969D01*
Y-42023D01*
Y-42077D01*
Y-42131D01*
Y-42185D01*
Y-42239D01*
Y-42293D01*
Y-42347D01*
Y-42401D01*
Y-42455D01*
Y-42509D01*
Y-42564D01*
Y-42618D01*
Y-42672D01*
Y-42726D01*
Y-42780D01*
Y-42834D01*
Y-42888D01*
Y-42942D01*
Y-42996D01*
Y-43050D01*
Y-43104D01*
Y-43158D01*
Y-43212D01*
Y-43266D01*
Y-43320D01*
Y-43374D01*
Y-43429D01*
Y-43483D01*
Y-43537D01*
Y-43591D01*
Y-43645D01*
Y-43699D01*
Y-43753D01*
Y-43807D01*
Y-43861D01*
Y-43915D01*
Y-43969D01*
Y-44023D01*
Y-44077D01*
Y-44131D01*
Y-44185D01*
Y-44239D01*
Y-44293D01*
Y-44348D01*
Y-44402D01*
Y-44456D01*
Y-44510D01*
Y-44564D01*
Y-44618D01*
Y-44672D01*
Y-44726D01*
Y-44780D01*
Y-44834D01*
Y-44888D01*
Y-44942D01*
Y-44996D01*
Y-45050D01*
Y-45104D01*
Y-45158D01*
Y-45213D01*
Y-45267D01*
Y-45321D01*
Y-45375D01*
Y-45429D01*
Y-45483D01*
Y-45537D01*
Y-45591D01*
Y-45645D01*
Y-45699D01*
Y-45753D01*
Y-45807D01*
Y-45861D01*
Y-45915D01*
Y-45969D01*
Y-46023D01*
Y-46077D01*
Y-46132D01*
Y-46186D01*
Y-46240D01*
Y-46294D01*
Y-46348D01*
Y-46402D01*
Y-46456D01*
Y-46510D01*
Y-46564D01*
Y-46618D01*
Y-46672D01*
Y-46726D01*
Y-46780D01*
Y-46834D01*
Y-46889D01*
Y-46942D01*
Y-46997D01*
Y-47051D01*
Y-47105D01*
Y-47159D01*
Y-47213D01*
Y-47267D01*
Y-47321D01*
Y-47375D01*
Y-47429D01*
Y-47483D01*
Y-47537D01*
Y-47591D01*
Y-47645D01*
Y-47699D01*
Y-47754D01*
Y-47807D01*
Y-47862D01*
Y-47916D01*
Y-47970D01*
Y-48024D01*
Y-48078D01*
Y-48132D01*
Y-48186D01*
Y-48240D01*
Y-48294D01*
Y-48348D01*
Y-48402D01*
Y-48456D01*
Y-48510D01*
Y-48564D01*
Y-48619D01*
Y-48673D01*
Y-48727D01*
Y-48781D01*
Y-48835D01*
Y-48889D01*
Y-48943D01*
Y-48997D01*
Y-49051D01*
Y-49105D01*
Y-49159D01*
Y-49213D01*
Y-49267D01*
Y-49321D01*
Y-49375D01*
Y-49429D01*
Y-49483D01*
Y-49538D01*
Y-49592D01*
Y-49646D01*
Y-49700D01*
Y-49754D01*
Y-49808D01*
Y-49862D01*
Y-49916D01*
Y-49970D01*
Y-50024D01*
Y-50078D01*
Y-50132D01*
Y-50186D01*
Y-50240D01*
Y-50294D01*
Y-50348D01*
Y-50402D01*
Y-50457D01*
Y-50511D01*
Y-50565D01*
Y-50619D01*
Y-50673D01*
Y-50727D01*
Y-50781D01*
Y-50835D01*
Y-50889D01*
Y-50943D01*
Y-50997D01*
Y-51051D01*
Y-51105D01*
Y-51159D01*
Y-51213D01*
Y-51267D01*
Y-51322D01*
Y-51376D01*
Y-51430D01*
Y-51484D01*
Y-51538D01*
Y-51592D01*
Y-51646D01*
Y-51700D01*
Y-51754D01*
Y-51808D01*
Y-51862D01*
Y-51916D01*
Y-51970D01*
Y-52024D01*
Y-52078D01*
Y-52132D01*
Y-52187D01*
Y-52241D01*
Y-52295D01*
Y-52349D01*
Y-52403D01*
Y-52457D01*
Y-52511D01*
Y-52565D01*
Y-52619D01*
Y-52673D01*
Y-52727D01*
Y-52781D01*
Y-52835D01*
Y-52889D01*
Y-52943D01*
Y-52997D01*
Y-53052D01*
Y-53106D01*
Y-53160D01*
Y-53214D01*
Y-53268D01*
Y-53322D01*
Y-53376D01*
Y-53430D01*
Y-53484D01*
Y-53538D01*
Y-53592D01*
Y-53646D01*
Y-53700D01*
Y-53754D01*
Y-53808D01*
Y-53863D01*
Y-53917D01*
Y-53971D01*
Y-54025D01*
Y-54079D01*
Y-54133D01*
Y-54187D01*
Y-54241D01*
Y-54295D01*
Y-54349D01*
Y-54403D01*
Y-54457D01*
Y-54511D01*
Y-54565D01*
Y-54619D01*
Y-54673D01*
Y-54728D01*
Y-54782D01*
Y-54836D01*
Y-54890D01*
Y-54944D01*
Y-54998D01*
Y-55052D01*
Y-55106D01*
Y-55160D01*
Y-55214D01*
Y-55268D01*
Y-55322D01*
Y-55376D01*
Y-55430D01*
Y-55484D01*
Y-55538D01*
Y-55592D01*
Y-55647D01*
Y-55701D01*
Y-55755D01*
Y-55809D01*
Y-55863D01*
Y-55917D01*
Y-55971D01*
Y-56025D01*
Y-56079D01*
Y-56133D01*
Y-56187D01*
Y-56241D01*
Y-56295D01*
Y-56349D01*
Y-56403D01*
Y-56457D01*
Y-56511D01*
Y-56566D01*
Y-56620D01*
Y-56674D01*
Y-56728D01*
Y-56782D01*
Y-56836D01*
Y-56890D01*
Y-56944D01*
Y-56998D01*
Y-57052D01*
Y-57106D01*
Y-57160D01*
Y-57214D01*
Y-57268D01*
Y-57322D01*
Y-57376D01*
Y-57431D01*
Y-57485D01*
Y-57539D01*
Y-57593D01*
Y-57647D01*
Y-57701D01*
Y-57755D01*
Y-57809D01*
Y-57863D01*
Y-57917D01*
Y-57971D01*
Y-58025D01*
Y-58079D01*
Y-58133D01*
Y-58187D01*
Y-58241D01*
Y-58296D01*
Y-58350D01*
Y-58404D01*
Y-58458D01*
Y-58512D01*
Y-58566D01*
Y-58620D01*
Y-58674D01*
Y-58728D01*
Y-58782D01*
Y-58836D01*
Y-58890D01*
Y-58944D01*
Y-58998D01*
Y-59052D01*
Y-59106D01*
Y-59161D01*
Y-59215D01*
Y-59269D01*
Y-59323D01*
Y-59377D01*
Y-59431D01*
Y-59485D01*
Y-59539D01*
Y-59593D01*
Y-59647D01*
Y-59701D01*
Y-59755D01*
Y-59809D01*
Y-59863D01*
Y-59917D01*
Y-59971D01*
Y-60026D01*
Y-60080D01*
Y-60134D01*
Y-60188D01*
Y-60242D01*
Y-60296D01*
Y-60350D01*
Y-60404D01*
Y-60458D01*
Y-60512D01*
Y-60566D01*
Y-60620D01*
Y-60674D01*
Y-60728D01*
Y-60782D01*
Y-60836D01*
Y-60891D01*
Y-60945D01*
Y-60999D01*
Y-61053D01*
Y-61107D01*
Y-61161D01*
Y-61215D01*
Y-61269D01*
Y-61323D01*
Y-61377D01*
Y-61431D01*
Y-61485D01*
Y-61539D01*
Y-61593D01*
Y-61647D01*
Y-61702D01*
Y-61756D01*
Y-61810D01*
Y-61864D01*
Y-61918D01*
Y-61972D01*
Y-62026D01*
Y-62080D01*
Y-62134D01*
Y-62188D01*
Y-62242D01*
Y-62296D01*
Y-62350D01*
Y-62404D01*
Y-62458D01*
Y-62512D01*
Y-62566D01*
Y-62621D01*
Y-62675D01*
Y-62729D01*
Y-62783D01*
Y-62837D01*
Y-62891D01*
Y-62945D01*
Y-62999D01*
Y-63053D01*
Y-63107D01*
Y-63161D01*
Y-63215D01*
Y-63269D01*
Y-63323D01*
Y-63377D01*
Y-63431D01*
Y-63485D01*
Y-63540D01*
Y-63594D01*
Y-63648D01*
Y-63702D01*
Y-63756D01*
Y-63810D01*
Y-63864D01*
Y-63918D01*
Y-63972D01*
Y-64026D01*
Y-64080D01*
Y-64134D01*
Y-64188D01*
Y-64242D01*
Y-64296D01*
Y-64350D01*
Y-64405D01*
Y-64459D01*
Y-64513D01*
Y-64567D01*
Y-64621D01*
Y-64675D01*
Y-64729D01*
Y-64783D01*
Y-64837D01*
Y-64891D01*
Y-64945D01*
Y-64999D01*
Y-65053D01*
Y-65107D01*
Y-65161D01*
Y-65215D01*
Y-65270D01*
Y-65324D01*
Y-65378D01*
Y-65432D01*
Y-65486D01*
Y-65540D01*
Y-65594D01*
Y-65648D01*
Y-65702D01*
Y-65756D01*
Y-65810D01*
Y-65864D01*
Y-65918D01*
Y-65972D01*
Y-66026D01*
Y-66080D01*
Y-66135D01*
Y-66189D01*
Y-66243D01*
Y-66297D01*
Y-66351D01*
Y-66405D01*
Y-66459D01*
Y-66513D01*
Y-66567D01*
Y-66621D01*
Y-66675D01*
Y-66729D01*
Y-66783D01*
Y-66837D01*
Y-66891D01*
Y-66945D01*
Y-67000D01*
Y-67054D01*
Y-67108D01*
Y-67162D01*
Y-67216D01*
Y-67270D01*
Y-67324D01*
Y-67378D01*
Y-67432D01*
Y-67486D01*
Y-67540D01*
Y-67594D01*
Y-67648D01*
Y-67702D01*
Y-67756D01*
Y-67810D01*
Y-67865D01*
Y-67919D01*
Y-67973D01*
Y-68027D01*
Y-68081D01*
Y-68135D01*
Y-68189D01*
Y-68243D01*
Y-68297D01*
Y-68351D01*
Y-68405D01*
Y-68459D01*
Y-68513D01*
Y-68567D01*
Y-68621D01*
Y-68676D01*
Y-68730D01*
Y-68784D01*
Y-68838D01*
Y-68892D01*
Y-68946D01*
Y-69000D01*
Y-69054D01*
Y-69108D01*
Y-69162D01*
Y-69216D01*
Y-69270D01*
Y-69324D01*
Y-69378D01*
Y-69432D01*
Y-69486D01*
X397352D01*
Y-69432D01*
Y-69378D01*
Y-69324D01*
Y-69270D01*
Y-69216D01*
Y-69162D01*
Y-69108D01*
Y-69054D01*
Y-69000D01*
Y-68946D01*
Y-68892D01*
Y-68838D01*
Y-68784D01*
Y-68730D01*
Y-68676D01*
Y-68621D01*
Y-68567D01*
Y-68513D01*
Y-68459D01*
Y-68405D01*
Y-68351D01*
Y-68297D01*
Y-68243D01*
Y-68189D01*
Y-68135D01*
Y-68081D01*
Y-68027D01*
Y-67973D01*
Y-67919D01*
Y-67865D01*
Y-67810D01*
Y-67756D01*
Y-67702D01*
Y-67648D01*
Y-67594D01*
Y-67540D01*
Y-67486D01*
Y-67432D01*
Y-67378D01*
Y-67324D01*
Y-67270D01*
Y-67216D01*
Y-67162D01*
Y-67108D01*
Y-67054D01*
Y-67000D01*
Y-66945D01*
Y-66891D01*
Y-66837D01*
Y-66783D01*
Y-66729D01*
Y-66675D01*
Y-66621D01*
Y-66567D01*
Y-66513D01*
Y-66459D01*
Y-66405D01*
Y-66351D01*
Y-66297D01*
Y-66243D01*
Y-66189D01*
Y-66135D01*
Y-66080D01*
Y-66026D01*
Y-65972D01*
Y-65918D01*
Y-65864D01*
Y-65810D01*
Y-65756D01*
Y-65702D01*
Y-65648D01*
Y-65594D01*
Y-65540D01*
Y-65486D01*
Y-65432D01*
Y-65378D01*
Y-65324D01*
Y-65270D01*
Y-65215D01*
Y-65161D01*
Y-65107D01*
Y-65053D01*
Y-64999D01*
Y-64945D01*
Y-64891D01*
Y-64837D01*
Y-64783D01*
Y-64729D01*
Y-64675D01*
Y-64621D01*
Y-64567D01*
Y-64513D01*
Y-64459D01*
Y-64405D01*
Y-64350D01*
Y-64296D01*
Y-64242D01*
Y-64188D01*
Y-64134D01*
Y-64080D01*
Y-64026D01*
Y-63972D01*
Y-63918D01*
Y-63864D01*
Y-63810D01*
Y-63756D01*
Y-63702D01*
Y-63648D01*
Y-63594D01*
Y-63540D01*
Y-63485D01*
Y-63431D01*
Y-63377D01*
Y-63323D01*
Y-63269D01*
Y-63215D01*
Y-63161D01*
Y-63107D01*
Y-63053D01*
Y-62999D01*
Y-62945D01*
Y-62891D01*
Y-62837D01*
Y-62783D01*
Y-62729D01*
Y-62675D01*
Y-62621D01*
Y-62566D01*
Y-62512D01*
Y-62458D01*
Y-62404D01*
Y-62350D01*
Y-62296D01*
Y-62242D01*
Y-62188D01*
Y-62134D01*
Y-62080D01*
Y-62026D01*
Y-61972D01*
Y-61918D01*
Y-61864D01*
Y-61810D01*
Y-61756D01*
Y-61702D01*
Y-61647D01*
Y-61593D01*
Y-61539D01*
Y-61485D01*
Y-61431D01*
Y-61377D01*
Y-61323D01*
Y-61269D01*
Y-61215D01*
Y-61161D01*
Y-61107D01*
Y-61053D01*
Y-60999D01*
Y-60945D01*
Y-60891D01*
Y-60836D01*
Y-60782D01*
Y-60728D01*
Y-60674D01*
Y-60620D01*
Y-60566D01*
Y-60512D01*
Y-60458D01*
Y-60404D01*
Y-60350D01*
Y-60296D01*
Y-60242D01*
Y-60188D01*
Y-60134D01*
Y-60080D01*
Y-60026D01*
Y-59971D01*
Y-59917D01*
Y-59863D01*
Y-59809D01*
Y-59755D01*
Y-59701D01*
Y-59647D01*
Y-59593D01*
Y-59539D01*
Y-59485D01*
Y-59431D01*
Y-59377D01*
Y-59323D01*
Y-59269D01*
Y-59215D01*
Y-59161D01*
Y-59106D01*
Y-59052D01*
Y-58998D01*
Y-58944D01*
Y-58890D01*
Y-58836D01*
Y-58782D01*
Y-58728D01*
Y-58674D01*
Y-58620D01*
Y-58566D01*
Y-58512D01*
Y-58458D01*
Y-58404D01*
Y-58350D01*
Y-58296D01*
Y-58241D01*
Y-58187D01*
Y-58133D01*
Y-58079D01*
Y-58025D01*
Y-57971D01*
Y-57917D01*
Y-57863D01*
Y-57809D01*
Y-57755D01*
Y-57701D01*
Y-57647D01*
Y-57593D01*
Y-57539D01*
Y-57485D01*
Y-57431D01*
Y-57376D01*
Y-57322D01*
Y-57268D01*
Y-57214D01*
Y-57160D01*
Y-57106D01*
Y-57052D01*
Y-56998D01*
Y-56944D01*
Y-56890D01*
Y-56836D01*
Y-56782D01*
Y-56728D01*
Y-56674D01*
Y-56620D01*
Y-56566D01*
Y-56511D01*
Y-56457D01*
Y-56403D01*
Y-56349D01*
Y-56295D01*
Y-56241D01*
Y-56187D01*
Y-56133D01*
Y-56079D01*
Y-56025D01*
Y-55971D01*
Y-55917D01*
Y-55863D01*
Y-55809D01*
Y-55755D01*
Y-55701D01*
Y-55647D01*
Y-55592D01*
Y-55538D01*
Y-55484D01*
Y-55430D01*
Y-55376D01*
Y-55322D01*
Y-55268D01*
Y-55214D01*
Y-55160D01*
Y-55106D01*
Y-55052D01*
Y-54998D01*
Y-54944D01*
Y-54890D01*
Y-54836D01*
Y-54782D01*
Y-54728D01*
Y-54673D01*
Y-54619D01*
Y-54565D01*
Y-54511D01*
Y-54457D01*
Y-54403D01*
Y-54349D01*
Y-54295D01*
Y-54241D01*
Y-54187D01*
Y-54133D01*
Y-54079D01*
Y-54025D01*
Y-53971D01*
Y-53917D01*
Y-53863D01*
Y-53808D01*
Y-53754D01*
Y-53700D01*
Y-53646D01*
Y-53592D01*
Y-53538D01*
Y-53484D01*
Y-53430D01*
Y-53376D01*
Y-53322D01*
Y-53268D01*
Y-53214D01*
Y-53160D01*
Y-53106D01*
Y-53052D01*
Y-52997D01*
Y-52943D01*
Y-52889D01*
Y-52835D01*
Y-52781D01*
Y-52727D01*
Y-52673D01*
Y-52619D01*
Y-52565D01*
Y-52511D01*
Y-52457D01*
Y-52403D01*
Y-52349D01*
Y-52295D01*
Y-52241D01*
Y-52187D01*
Y-52132D01*
Y-52078D01*
Y-52024D01*
Y-51970D01*
Y-51916D01*
Y-51862D01*
Y-51808D01*
Y-51754D01*
Y-51700D01*
Y-51646D01*
Y-51592D01*
Y-51538D01*
Y-51484D01*
Y-51430D01*
Y-51376D01*
Y-51322D01*
Y-51267D01*
Y-51213D01*
Y-51159D01*
Y-51105D01*
Y-51051D01*
Y-50997D01*
Y-50943D01*
Y-50889D01*
Y-50835D01*
Y-50781D01*
Y-50727D01*
Y-50673D01*
Y-50619D01*
Y-50565D01*
Y-50511D01*
Y-50457D01*
Y-50402D01*
Y-50348D01*
Y-50294D01*
Y-50240D01*
Y-50186D01*
Y-50132D01*
Y-50078D01*
Y-50024D01*
Y-49970D01*
Y-49916D01*
Y-49862D01*
Y-49808D01*
Y-49754D01*
Y-49700D01*
Y-49646D01*
Y-49592D01*
Y-49538D01*
Y-49483D01*
Y-49429D01*
Y-49375D01*
Y-49321D01*
Y-49267D01*
Y-49213D01*
Y-49159D01*
Y-49105D01*
Y-49051D01*
Y-48997D01*
Y-48943D01*
Y-48889D01*
Y-48835D01*
Y-48781D01*
Y-48727D01*
Y-48673D01*
Y-48619D01*
Y-48564D01*
Y-48510D01*
Y-48456D01*
Y-48402D01*
Y-48348D01*
Y-48294D01*
Y-48240D01*
Y-48186D01*
Y-48132D01*
Y-48078D01*
Y-48024D01*
Y-47970D01*
Y-47916D01*
Y-47862D01*
Y-47807D01*
Y-47754D01*
Y-47699D01*
Y-47645D01*
Y-47591D01*
Y-47537D01*
Y-47483D01*
Y-47429D01*
Y-47375D01*
Y-47321D01*
Y-47267D01*
Y-47213D01*
Y-47159D01*
Y-47105D01*
Y-47051D01*
Y-46997D01*
Y-46942D01*
Y-46889D01*
Y-46834D01*
Y-46780D01*
Y-46726D01*
Y-46672D01*
Y-46618D01*
Y-46564D01*
Y-46510D01*
Y-46456D01*
Y-46402D01*
Y-46348D01*
Y-46294D01*
Y-46240D01*
Y-46186D01*
Y-46132D01*
Y-46077D01*
Y-46023D01*
Y-45969D01*
Y-45915D01*
Y-45861D01*
Y-45807D01*
Y-45753D01*
Y-45699D01*
Y-45645D01*
Y-45591D01*
Y-45537D01*
Y-45483D01*
Y-45429D01*
Y-45375D01*
Y-45321D01*
Y-45267D01*
Y-45213D01*
Y-45158D01*
Y-45104D01*
Y-45050D01*
Y-44996D01*
Y-44942D01*
Y-44888D01*
Y-44834D01*
Y-44780D01*
Y-44726D01*
Y-44672D01*
Y-44618D01*
Y-44564D01*
Y-44510D01*
Y-44456D01*
Y-44402D01*
Y-44348D01*
Y-44293D01*
Y-44239D01*
Y-44185D01*
Y-44131D01*
Y-44077D01*
Y-44023D01*
Y-43969D01*
Y-43915D01*
Y-43861D01*
Y-43807D01*
Y-43753D01*
Y-43699D01*
Y-43645D01*
Y-43591D01*
Y-43537D01*
Y-43483D01*
Y-43429D01*
Y-43374D01*
Y-43320D01*
Y-43266D01*
Y-43212D01*
Y-43158D01*
Y-43104D01*
Y-43050D01*
Y-42996D01*
Y-42942D01*
Y-42888D01*
Y-42834D01*
Y-42780D01*
Y-42726D01*
Y-42672D01*
Y-42618D01*
Y-42564D01*
Y-42509D01*
Y-42455D01*
Y-42401D01*
Y-42347D01*
Y-42293D01*
Y-42239D01*
Y-42185D01*
Y-42131D01*
Y-42077D01*
Y-42023D01*
Y-41969D01*
Y-41915D01*
Y-41861D01*
Y-41807D01*
Y-41753D01*
Y-41699D01*
Y-41644D01*
Y-41590D01*
Y-41536D01*
Y-41482D01*
Y-41428D01*
Y-41374D01*
Y-41320D01*
Y-41266D01*
Y-41212D01*
Y-41158D01*
Y-41104D01*
Y-41050D01*
Y-40996D01*
Y-40942D01*
Y-40888D01*
Y-40834D01*
Y-40780D01*
Y-40725D01*
Y-40671D01*
Y-40617D01*
Y-40563D01*
Y-40509D01*
Y-40455D01*
Y-40401D01*
Y-40347D01*
Y-40293D01*
Y-40239D01*
Y-40185D01*
Y-40131D01*
Y-40077D01*
Y-40023D01*
Y-39968D01*
Y-39915D01*
Y-39860D01*
Y-39806D01*
Y-39752D01*
Y-39698D01*
Y-39644D01*
Y-39590D01*
Y-39536D01*
Y-39482D01*
Y-39428D01*
Y-39374D01*
Y-39320D01*
Y-39266D01*
Y-39212D01*
Y-39158D01*
Y-39103D01*
Y-39050D01*
Y-38995D01*
Y-38941D01*
Y-38887D01*
Y-38833D01*
Y-38779D01*
Y-38725D01*
Y-38671D01*
Y-38617D01*
Y-38563D01*
Y-38509D01*
Y-38455D01*
Y-38401D01*
Y-38347D01*
Y-38293D01*
Y-38238D01*
Y-38184D01*
Y-38130D01*
Y-38076D01*
Y-38022D01*
Y-37968D01*
Y-37914D01*
Y-37860D01*
Y-37806D01*
Y-37752D01*
Y-37698D01*
Y-37644D01*
Y-37590D01*
Y-37536D01*
Y-37482D01*
Y-37428D01*
Y-37374D01*
Y-37319D01*
Y-37265D01*
Y-37211D01*
Y-37157D01*
Y-37103D01*
Y-37049D01*
Y-36995D01*
Y-36941D01*
Y-36887D01*
Y-36833D01*
Y-36779D01*
Y-36725D01*
Y-36671D01*
Y-36617D01*
Y-36563D01*
Y-36509D01*
Y-36454D01*
Y-36400D01*
Y-36346D01*
Y-36292D01*
Y-36238D01*
Y-36184D01*
Y-36130D01*
Y-36076D01*
Y-36022D01*
Y-35968D01*
Y-35914D01*
Y-35860D01*
Y-35806D01*
Y-35752D01*
Y-35698D01*
Y-35644D01*
Y-35590D01*
Y-35535D01*
Y-35481D01*
Y-35427D01*
Y-35373D01*
Y-35319D01*
Y-35265D01*
Y-35211D01*
Y-35157D01*
Y-35103D01*
Y-35049D01*
Y-34995D01*
Y-34941D01*
Y-34887D01*
Y-34833D01*
Y-34779D01*
Y-34725D01*
Y-34670D01*
Y-34616D01*
Y-34562D01*
Y-34508D01*
Y-34454D01*
Y-34400D01*
Y-34346D01*
Y-34292D01*
Y-34238D01*
Y-34184D01*
Y-34130D01*
Y-34076D01*
Y-34022D01*
Y-33968D01*
Y-33914D01*
Y-33860D01*
Y-33806D01*
Y-33751D01*
Y-33697D01*
Y-33643D01*
Y-33589D01*
Y-33535D01*
Y-33481D01*
Y-33427D01*
Y-33373D01*
Y-33319D01*
Y-33265D01*
Y-33211D01*
Y-33157D01*
Y-33103D01*
Y-33049D01*
Y-32994D01*
Y-32941D01*
Y-32886D01*
Y-32832D01*
Y-32778D01*
Y-32724D01*
Y-32670D01*
Y-32616D01*
Y-32562D01*
Y-32508D01*
Y-32454D01*
Y-32400D01*
Y-32346D01*
Y-32292D01*
Y-32238D01*
Y-32184D01*
Y-32129D01*
Y-32076D01*
Y-32021D01*
Y-31967D01*
Y-31913D01*
Y-31859D01*
Y-31805D01*
Y-31751D01*
Y-31697D01*
Y-31643D01*
Y-31589D01*
Y-31535D01*
Y-31481D01*
Y-31427D01*
Y-31373D01*
Y-31319D01*
Y-31265D01*
Y-31211D01*
Y-31156D01*
Y-31102D01*
Y-31048D01*
Y-30994D01*
Y-30940D01*
Y-30886D01*
Y-30832D01*
Y-30778D01*
Y-30724D01*
Y-30670D01*
Y-30616D01*
Y-30562D01*
Y-30508D01*
Y-30454D01*
Y-30400D01*
Y-30345D01*
Y-30291D01*
Y-30237D01*
Y-30183D01*
Y-30129D01*
Y-30075D01*
Y-30021D01*
Y-29967D01*
Y-29913D01*
Y-29859D01*
Y-29805D01*
Y-29751D01*
Y-29697D01*
Y-29643D01*
Y-29589D01*
Y-29535D01*
Y-29480D01*
Y-29426D01*
Y-29372D01*
Y-29318D01*
Y-29264D01*
Y-29210D01*
Y-29156D01*
Y-29102D01*
Y-29048D01*
Y-28994D01*
Y-28940D01*
Y-28886D01*
Y-28832D01*
Y-28778D01*
Y-28724D01*
Y-28670D01*
Y-28615D01*
Y-28561D01*
Y-28507D01*
Y-28453D01*
Y-28399D01*
Y-28345D01*
Y-28291D01*
Y-28237D01*
Y-28183D01*
Y-28129D01*
Y-28075D01*
Y-28021D01*
Y-27967D01*
Y-27913D01*
Y-27859D01*
Y-27805D01*
Y-27751D01*
Y-27696D01*
Y-27642D01*
Y-27588D01*
Y-27534D01*
Y-27480D01*
Y-27426D01*
Y-27372D01*
Y-27318D01*
Y-27264D01*
Y-27210D01*
Y-27156D01*
Y-27102D01*
Y-27048D01*
Y-26994D01*
Y-26940D01*
Y-26886D01*
Y-26831D01*
Y-26777D01*
Y-26723D01*
Y-26669D01*
Y-26615D01*
Y-26561D01*
Y-26507D01*
Y-26453D01*
Y-26399D01*
Y-26345D01*
Y-26291D01*
Y-26237D01*
Y-26183D01*
Y-26129D01*
Y-26075D01*
Y-26021D01*
Y-25967D01*
Y-25912D01*
Y-25858D01*
Y-25804D01*
Y-25750D01*
Y-25696D01*
Y-25642D01*
Y-25588D01*
Y-25534D01*
Y-25480D01*
Y-25426D01*
Y-25372D01*
Y-25318D01*
Y-25264D01*
Y-25210D01*
Y-25155D01*
Y-25102D01*
Y-25047D01*
Y-24993D01*
Y-24939D01*
Y-24885D01*
Y-24831D01*
Y-24777D01*
Y-24723D01*
Y-24669D01*
Y-24615D01*
Y-24561D01*
Y-24507D01*
Y-24453D01*
Y-24399D01*
Y-24345D01*
Y-24291D01*
Y-24237D01*
Y-24182D01*
Y-24128D01*
Y-24074D01*
Y-24020D01*
Y-23966D01*
Y-23912D01*
Y-23858D01*
Y-23804D01*
Y-23750D01*
Y-23696D01*
Y-23642D01*
Y-23588D01*
Y-23534D01*
Y-23480D01*
Y-23426D01*
Y-23371D01*
Y-23317D01*
Y-23263D01*
Y-23209D01*
Y-23155D01*
Y-23101D01*
Y-23047D01*
Y-22993D01*
Y-22939D01*
Y-22885D01*
Y-22831D01*
Y-22777D01*
Y-22723D01*
Y-22669D01*
Y-22615D01*
Y-22561D01*
Y-22506D01*
Y-22452D01*
Y-22398D01*
Y-22344D01*
Y-22290D01*
Y-22236D01*
Y-22182D01*
Y-22128D01*
Y-22074D01*
Y-22020D01*
Y-21966D01*
Y-21912D01*
Y-21858D01*
Y-21804D01*
Y-21750D01*
Y-21696D01*
Y-21642D01*
Y-21587D01*
Y-21533D01*
Y-21479D01*
Y-21425D01*
Y-21371D01*
Y-21317D01*
Y-21263D01*
Y-21209D01*
Y-21155D01*
Y-21101D01*
Y-21047D01*
Y-20993D01*
Y-20939D01*
Y-20885D01*
Y-20831D01*
Y-20776D01*
Y-20722D01*
Y-20668D01*
Y-20614D01*
Y-20560D01*
Y-20506D01*
Y-20452D01*
Y-20398D01*
Y-20344D01*
Y-20290D01*
Y-20236D01*
Y-20182D01*
Y-20128D01*
Y-20074D01*
Y-20020D01*
Y-19966D01*
Y-19911D01*
Y-19858D01*
Y-19803D01*
Y-19749D01*
Y-19695D01*
Y-19641D01*
Y-19587D01*
Y-19533D01*
Y-19479D01*
Y-19425D01*
Y-19371D01*
Y-19317D01*
Y-19263D01*
Y-19209D01*
Y-19155D01*
Y-19101D01*
Y-19047D01*
Y-18993D01*
Y-18938D01*
Y-18884D01*
Y-18830D01*
Y-18776D01*
Y-18722D01*
Y-18668D01*
Y-18614D01*
Y-18560D01*
Y-18506D01*
Y-18452D01*
Y-18398D01*
Y-18344D01*
Y-18290D01*
Y-18236D01*
Y-18181D01*
Y-18127D01*
Y-18073D01*
Y-18019D01*
Y-17965D01*
Y-17911D01*
Y-17857D01*
Y-17803D01*
Y-17749D01*
Y-17695D01*
Y-17641D01*
Y-17587D01*
Y-17533D01*
Y-17479D01*
Y-17425D01*
Y-17371D01*
Y-17317D01*
Y-17263D01*
Y-17208D01*
Y-17154D01*
Y-17100D01*
Y-17046D01*
Y-16992D01*
Y-16938D01*
Y-16884D01*
Y-16830D01*
Y-16776D01*
Y-16722D01*
Y-16668D01*
Y-16614D01*
Y-16560D01*
Y-16506D01*
Y-16452D01*
Y-16398D01*
Y-16343D01*
Y-16289D01*
Y-16235D01*
Y-16181D01*
Y-16127D01*
Y-16073D01*
Y-16019D01*
Y-15965D01*
Y-15911D01*
Y-15857D01*
Y-15803D01*
Y-15749D01*
Y-15695D01*
Y-15641D01*
Y-15587D01*
Y-15532D01*
Y-15478D01*
Y-15424D01*
Y-15370D01*
Y-15316D01*
Y-15262D01*
Y-15208D01*
Y-15154D01*
Y-15100D01*
Y-15046D01*
Y-14992D01*
Y-14938D01*
Y-14884D01*
Y-14830D01*
Y-14776D01*
Y-14722D01*
Y-14668D01*
Y-14614D01*
Y-14559D01*
Y-14505D01*
Y-14451D01*
Y-14397D01*
Y-14343D01*
Y-14289D01*
Y-14235D01*
Y-14181D01*
Y-14127D01*
Y-14073D01*
Y-14019D01*
Y-13965D01*
Y-13911D01*
Y-13857D01*
Y-13803D01*
Y-13748D01*
Y-13694D01*
Y-13640D01*
Y-13586D01*
Y-13532D01*
Y-13478D01*
Y-13424D01*
Y-13370D01*
Y-13316D01*
Y-13262D01*
Y-13208D01*
Y-13154D01*
Y-13100D01*
Y-13046D01*
Y-12992D01*
Y-12937D01*
Y-12883D01*
Y-12829D01*
Y-12775D01*
Y-12721D01*
Y-12667D01*
Y-12613D01*
Y-12559D01*
Y-12505D01*
Y-12451D01*
Y-12397D01*
Y-12343D01*
Y-12289D01*
Y-12235D01*
Y-12181D01*
Y-12127D01*
Y-12072D01*
Y-12019D01*
Y-11964D01*
Y-11910D01*
Y-11856D01*
Y-11802D01*
Y-11748D01*
Y-11694D01*
Y-11640D01*
Y-11586D01*
Y-11532D01*
Y-11478D01*
Y-11424D01*
Y-11370D01*
Y-11316D01*
Y-11262D01*
Y-11208D01*
Y-11153D01*
Y-11099D01*
Y-11045D01*
Y-10991D01*
Y-10937D01*
Y-10883D01*
Y-10829D01*
Y-10775D01*
Y-10721D01*
Y-10667D01*
Y-10613D01*
Y-10559D01*
Y-10505D01*
Y-10451D01*
X397406D01*
Y-10397D01*
Y-10343D01*
Y-10289D01*
Y-10234D01*
Y-10180D01*
X397460D01*
Y-10126D01*
Y-10072D01*
Y-10018D01*
Y-9964D01*
X397514D01*
Y-9910D01*
Y-9856D01*
X397568D01*
Y-9802D01*
Y-9748D01*
Y-9694D01*
X397622D01*
Y-9640D01*
Y-9586D01*
X397676D01*
Y-9532D01*
Y-9478D01*
X397730D01*
Y-9424D01*
Y-9369D01*
X397784D01*
Y-9315D01*
Y-9261D01*
X397839D01*
Y-9207D01*
X397893D01*
Y-9153D01*
Y-9099D01*
X397947D01*
Y-9045D01*
X398001D01*
Y-8991D01*
X398055D01*
Y-8937D01*
Y-8883D01*
X398109D01*
Y-8829D01*
X398163D01*
Y-8775D01*
X398217D01*
Y-8721D01*
X398271D01*
Y-8667D01*
X398325D01*
Y-8613D01*
X398379D01*
Y-8558D01*
X398433D01*
Y-8504D01*
X398487D01*
Y-8450D01*
X398595D01*
Y-8396D01*
X398650D01*
Y-8342D01*
X398704D01*
Y-8288D01*
X398812D01*
Y-8234D01*
X398866D01*
Y-8180D01*
X398974D01*
Y-8126D01*
X399082D01*
Y-8072D01*
X399190D01*
Y-8018D01*
X399298D01*
Y-7964D01*
X399460D01*
Y-7910D01*
X399569D01*
Y-7856D01*
X399785D01*
Y-7802D01*
X400001D01*
Y-7748D01*
X400542D01*
Y-7694D01*
X407408D01*
Y-7748D01*
D02*
G37*
%LPC*%
G36*
X362969Y-12181D02*
X360968D01*
Y-12235D01*
X360157D01*
Y-12289D01*
X359671D01*
Y-12343D01*
X359238D01*
Y-12397D01*
X358806D01*
Y-12451D01*
X358481D01*
Y-12505D01*
X358157D01*
Y-12559D01*
X357887D01*
Y-12613D01*
X357616D01*
Y-12667D01*
X357346D01*
Y-12721D01*
X357130D01*
Y-12775D01*
X356914D01*
Y-12829D01*
X356697D01*
Y-12883D01*
X356481D01*
Y-12937D01*
X356319D01*
Y-12992D01*
X356103D01*
Y-13046D01*
X355941D01*
Y-13100D01*
X355778D01*
Y-13154D01*
X355562D01*
Y-13208D01*
X355400D01*
Y-13262D01*
X355238D01*
Y-13316D01*
X355130D01*
Y-13370D01*
X354967D01*
Y-13424D01*
X354805D01*
Y-13478D01*
X354643D01*
Y-13532D01*
X354535D01*
Y-13586D01*
X354373D01*
Y-13640D01*
X354211D01*
Y-13694D01*
X354102D01*
Y-13748D01*
X353940D01*
Y-13803D01*
X353832D01*
Y-13857D01*
X353724D01*
Y-13911D01*
X353562D01*
Y-13965D01*
X353454D01*
Y-14019D01*
X353346D01*
Y-14073D01*
X353237D01*
Y-14127D01*
X353129D01*
Y-14181D01*
X352967D01*
Y-14235D01*
X352859D01*
Y-14289D01*
X352805D01*
Y-14343D01*
X352697D01*
Y-14397D01*
X352535D01*
Y-14451D01*
X352427D01*
Y-14505D01*
X352372D01*
Y-14559D01*
X352210D01*
Y-14614D01*
X352156D01*
Y-14668D01*
X352048D01*
Y-14722D01*
X351940D01*
Y-14776D01*
X351832D01*
Y-14830D01*
X351724D01*
Y-14884D01*
X351670D01*
Y-14938D01*
X351561D01*
Y-14992D01*
X351453D01*
Y-15046D01*
X351345D01*
Y-15100D01*
X351291D01*
Y-15154D01*
X351183D01*
Y-15208D01*
X351075D01*
Y-15262D01*
X351021D01*
Y-15316D01*
X350913D01*
Y-15370D01*
X350859D01*
Y-15424D01*
X350751D01*
Y-15478D01*
X350642D01*
Y-15532D01*
X350588D01*
Y-15587D01*
X350480D01*
Y-15641D01*
X350426D01*
Y-15695D01*
X350318D01*
Y-15749D01*
X350264D01*
Y-15803D01*
X350156D01*
Y-15857D01*
X350102D01*
Y-15911D01*
X349994D01*
Y-15965D01*
X349940D01*
Y-16019D01*
X349886D01*
Y-16073D01*
X349778D01*
Y-16127D01*
X349723D01*
Y-16181D01*
X349669D01*
Y-16235D01*
X349561D01*
Y-16289D01*
X349507D01*
Y-16343D01*
X349399D01*
Y-16398D01*
X349345D01*
Y-16452D01*
X349291D01*
Y-16506D01*
X349237D01*
Y-16560D01*
X349129D01*
Y-16614D01*
X349075D01*
Y-16668D01*
X349021D01*
Y-16722D01*
X348913D01*
Y-16776D01*
X348858D01*
Y-16830D01*
X348804D01*
Y-16884D01*
X348750D01*
Y-16938D01*
X348696D01*
Y-16992D01*
X348588D01*
Y-17046D01*
X348534D01*
Y-17100D01*
X348480D01*
Y-17154D01*
X348426D01*
Y-17208D01*
X348372D01*
Y-17263D01*
X348264D01*
Y-17317D01*
X348210D01*
Y-17371D01*
X348156D01*
Y-17425D01*
X348101D01*
Y-17479D01*
X348047D01*
Y-17533D01*
X347993D01*
Y-17587D01*
X347939D01*
Y-17641D01*
X347885D01*
Y-17695D01*
X347831D01*
Y-17749D01*
X347723D01*
Y-17803D01*
X347669D01*
Y-17857D01*
X347615D01*
Y-17911D01*
X347561D01*
Y-17965D01*
X347507D01*
Y-18019D01*
X347453D01*
Y-18073D01*
X347399D01*
Y-18127D01*
X347345D01*
Y-18181D01*
X347291D01*
Y-18236D01*
X347236D01*
Y-18290D01*
X347182D01*
Y-18344D01*
X347128D01*
Y-18398D01*
X347074D01*
Y-18452D01*
X347020D01*
Y-18506D01*
X346966D01*
Y-18560D01*
X346912D01*
Y-18614D01*
X346858D01*
Y-18668D01*
X346804D01*
Y-18722D01*
X346750D01*
Y-18776D01*
X346696D01*
Y-18830D01*
X346642D01*
Y-18884D01*
X346588D01*
Y-18938D01*
Y-18993D01*
X346534D01*
Y-19047D01*
X346480D01*
Y-19101D01*
X346426D01*
Y-19155D01*
X346372D01*
Y-19209D01*
X346318D01*
Y-19263D01*
X346263D01*
Y-19317D01*
X346209D01*
Y-19371D01*
X346155D01*
Y-19425D01*
Y-19479D01*
X346101D01*
Y-19533D01*
X346047D01*
Y-19587D01*
X345993D01*
Y-19641D01*
X345939D01*
Y-19695D01*
X345885D01*
Y-19749D01*
Y-19803D01*
X345831D01*
Y-19858D01*
X345777D01*
Y-19911D01*
X345723D01*
Y-19966D01*
X345669D01*
Y-20020D01*
X345615D01*
Y-20074D01*
Y-20128D01*
X345561D01*
Y-20182D01*
X345507D01*
Y-20236D01*
X345452D01*
Y-20290D01*
Y-20344D01*
X345398D01*
Y-20398D01*
X345344D01*
Y-20452D01*
X345290D01*
Y-20506D01*
X345236D01*
Y-20560D01*
Y-20614D01*
X345182D01*
Y-20668D01*
X345128D01*
Y-20722D01*
X345074D01*
Y-20776D01*
Y-20831D01*
X345020D01*
Y-20885D01*
X344966D01*
Y-20939D01*
Y-20993D01*
X344912D01*
Y-21047D01*
X344858D01*
Y-21101D01*
X344804D01*
Y-21155D01*
Y-21209D01*
X344750D01*
Y-21263D01*
X344696D01*
Y-21317D01*
Y-21371D01*
X344642D01*
Y-21425D01*
X344587D01*
Y-21479D01*
Y-21533D01*
X344533D01*
Y-21587D01*
X344479D01*
Y-21642D01*
Y-21696D01*
X344425D01*
Y-21750D01*
X344371D01*
Y-21804D01*
Y-21858D01*
X344317D01*
Y-21912D01*
X344263D01*
Y-21966D01*
Y-22020D01*
X344209D01*
Y-22074D01*
Y-22128D01*
X344155D01*
Y-22182D01*
X344101D01*
Y-22236D01*
Y-22290D01*
X344047D01*
Y-22344D01*
Y-22398D01*
X343993D01*
Y-22452D01*
X343939D01*
Y-22506D01*
Y-22561D01*
X343885D01*
Y-22615D01*
Y-22669D01*
X343831D01*
Y-22723D01*
X343777D01*
Y-22777D01*
Y-22831D01*
X343723D01*
Y-22885D01*
Y-22939D01*
X343669D01*
Y-22993D01*
Y-23047D01*
X343614D01*
Y-23101D01*
Y-23155D01*
X343560D01*
Y-23209D01*
X343506D01*
Y-23263D01*
Y-23317D01*
X343452D01*
Y-23371D01*
Y-23426D01*
X343398D01*
Y-23480D01*
Y-23534D01*
X343344D01*
Y-23588D01*
Y-23642D01*
X343290D01*
Y-23696D01*
Y-23750D01*
X343236D01*
Y-23804D01*
Y-23858D01*
X343182D01*
Y-23912D01*
Y-23966D01*
X343128D01*
Y-24020D01*
Y-24074D01*
X343074D01*
Y-24128D01*
Y-24182D01*
X343020D01*
Y-24237D01*
Y-24291D01*
Y-24345D01*
X342966D01*
Y-24399D01*
Y-24453D01*
X342912D01*
Y-24507D01*
Y-24561D01*
X342858D01*
Y-24615D01*
Y-24669D01*
X342804D01*
Y-24723D01*
Y-24777D01*
Y-24831D01*
X342749D01*
Y-24885D01*
Y-24939D01*
X342695D01*
Y-24993D01*
Y-25047D01*
X342641D01*
Y-25102D01*
Y-25155D01*
Y-25210D01*
X342587D01*
Y-25264D01*
Y-25318D01*
X342533D01*
Y-25372D01*
Y-25426D01*
Y-25480D01*
X342479D01*
Y-25534D01*
Y-25588D01*
X342425D01*
Y-25642D01*
Y-25696D01*
Y-25750D01*
X342371D01*
Y-25804D01*
Y-25858D01*
Y-25912D01*
X342317D01*
Y-25967D01*
Y-26021D01*
X342263D01*
Y-26075D01*
Y-26129D01*
Y-26183D01*
X342209D01*
Y-26237D01*
Y-26291D01*
Y-26345D01*
X342155D01*
Y-26399D01*
Y-26453D01*
Y-26507D01*
X342101D01*
Y-26561D01*
Y-26615D01*
Y-26669D01*
X342047D01*
Y-26723D01*
Y-26777D01*
Y-26831D01*
X341992D01*
Y-26886D01*
Y-26940D01*
Y-26994D01*
Y-27048D01*
X341938D01*
Y-27102D01*
Y-27156D01*
Y-27210D01*
X341884D01*
Y-27264D01*
Y-27318D01*
Y-27372D01*
Y-27426D01*
X341830D01*
Y-27480D01*
Y-27534D01*
Y-27588D01*
X341776D01*
Y-27642D01*
Y-27696D01*
Y-27751D01*
Y-27805D01*
X341722D01*
Y-27859D01*
Y-27913D01*
Y-27967D01*
Y-28021D01*
X341668D01*
Y-28075D01*
Y-28129D01*
Y-28183D01*
Y-28237D01*
X341614D01*
Y-28291D01*
Y-28345D01*
Y-28399D01*
Y-28453D01*
X341560D01*
Y-28507D01*
Y-28561D01*
Y-28615D01*
Y-28670D01*
Y-28724D01*
X341506D01*
Y-28778D01*
Y-28832D01*
Y-28886D01*
Y-28940D01*
Y-28994D01*
X341452D01*
Y-29048D01*
Y-29102D01*
Y-29156D01*
Y-29210D01*
Y-29264D01*
X341398D01*
Y-29318D01*
Y-29372D01*
Y-29426D01*
Y-29480D01*
Y-29535D01*
X341344D01*
Y-29589D01*
Y-29643D01*
Y-29697D01*
Y-29751D01*
Y-29805D01*
Y-29859D01*
X341290D01*
Y-29913D01*
Y-29967D01*
Y-30021D01*
Y-30075D01*
Y-30129D01*
Y-30183D01*
Y-30237D01*
X341236D01*
Y-30291D01*
Y-30345D01*
Y-30400D01*
Y-30454D01*
Y-30508D01*
Y-30562D01*
Y-30616D01*
Y-30670D01*
X341182D01*
Y-30724D01*
Y-30778D01*
Y-30832D01*
Y-30886D01*
Y-30940D01*
Y-30994D01*
Y-31048D01*
Y-31102D01*
Y-31156D01*
Y-31211D01*
X341127D01*
Y-31265D01*
Y-31319D01*
Y-31373D01*
Y-31427D01*
Y-31481D01*
Y-31535D01*
Y-31589D01*
Y-31643D01*
Y-31697D01*
Y-31751D01*
Y-31805D01*
Y-31859D01*
Y-31913D01*
Y-31967D01*
X341073D01*
Y-32021D01*
Y-32076D01*
Y-32129D01*
X341127D01*
Y-32184D01*
X341073D01*
Y-32238D01*
Y-32292D01*
Y-32346D01*
Y-32400D01*
Y-32454D01*
Y-32508D01*
Y-32562D01*
Y-32616D01*
Y-32670D01*
Y-32724D01*
Y-32778D01*
Y-32832D01*
X341722D01*
Y-32778D01*
Y-32724D01*
Y-32670D01*
Y-32616D01*
Y-32562D01*
Y-32508D01*
Y-32454D01*
Y-32400D01*
Y-32346D01*
Y-32292D01*
Y-32238D01*
X341776D01*
Y-32184D01*
Y-32129D01*
Y-32076D01*
Y-32021D01*
Y-31967D01*
Y-31913D01*
Y-31859D01*
Y-31805D01*
Y-31751D01*
Y-31697D01*
Y-31643D01*
Y-31589D01*
Y-31535D01*
Y-31481D01*
Y-31427D01*
Y-31373D01*
Y-31319D01*
X341830D01*
Y-31265D01*
Y-31211D01*
Y-31156D01*
Y-31102D01*
Y-31048D01*
Y-30994D01*
Y-30940D01*
Y-30886D01*
Y-30832D01*
X341884D01*
Y-30778D01*
Y-30724D01*
Y-30670D01*
Y-30616D01*
Y-30562D01*
Y-30508D01*
Y-30454D01*
Y-30400D01*
Y-30345D01*
X341938D01*
Y-30291D01*
Y-30237D01*
Y-30183D01*
Y-30129D01*
Y-30075D01*
Y-30021D01*
Y-29967D01*
X341992D01*
Y-29913D01*
Y-29859D01*
Y-29805D01*
Y-29751D01*
Y-29697D01*
Y-29643D01*
X342047D01*
Y-29589D01*
Y-29535D01*
Y-29480D01*
Y-29426D01*
Y-29372D01*
X342101D01*
Y-29318D01*
Y-29264D01*
Y-29210D01*
Y-29156D01*
Y-29102D01*
Y-29048D01*
X342155D01*
Y-28994D01*
Y-28940D01*
Y-28886D01*
Y-28832D01*
X342209D01*
Y-28778D01*
Y-28724D01*
Y-28670D01*
Y-28615D01*
Y-28561D01*
X342263D01*
Y-28507D01*
Y-28453D01*
Y-28399D01*
Y-28345D01*
X342317D01*
Y-28291D01*
Y-28237D01*
Y-28183D01*
Y-28129D01*
X342371D01*
Y-28075D01*
Y-28021D01*
Y-27967D01*
Y-27913D01*
X342425D01*
Y-27859D01*
Y-27805D01*
Y-27751D01*
Y-27696D01*
X342479D01*
Y-27642D01*
Y-27588D01*
Y-27534D01*
X342533D01*
Y-27480D01*
Y-27426D01*
Y-27372D01*
Y-27318D01*
X342587D01*
Y-27264D01*
Y-27210D01*
Y-27156D01*
X342641D01*
Y-27102D01*
Y-27048D01*
Y-26994D01*
X342695D01*
Y-26940D01*
Y-26886D01*
Y-26831D01*
Y-26777D01*
X342749D01*
Y-26723D01*
Y-26669D01*
Y-26615D01*
X342804D01*
Y-26561D01*
Y-26507D01*
Y-26453D01*
X342858D01*
Y-26399D01*
Y-26345D01*
X342912D01*
Y-26291D01*
Y-26237D01*
Y-26183D01*
X342966D01*
Y-26129D01*
Y-26075D01*
Y-26021D01*
X343020D01*
Y-25967D01*
Y-25912D01*
Y-25858D01*
X343074D01*
Y-25804D01*
Y-25750D01*
X343128D01*
Y-25696D01*
Y-25642D01*
Y-25588D01*
X343182D01*
Y-25534D01*
Y-25480D01*
X343236D01*
Y-25426D01*
Y-25372D01*
Y-25318D01*
X343290D01*
Y-25264D01*
Y-25210D01*
X343344D01*
Y-25155D01*
Y-25102D01*
X343398D01*
Y-25047D01*
Y-24993D01*
Y-24939D01*
X343452D01*
Y-24885D01*
Y-24831D01*
X343506D01*
Y-24777D01*
Y-24723D01*
X343560D01*
Y-24669D01*
Y-24615D01*
X343614D01*
Y-24561D01*
Y-24507D01*
X343669D01*
Y-24453D01*
Y-24399D01*
X343723D01*
Y-24345D01*
Y-24291D01*
Y-24237D01*
X343777D01*
Y-24182D01*
Y-24128D01*
X343831D01*
Y-24074D01*
Y-24020D01*
X343885D01*
Y-23966D01*
Y-23912D01*
X343939D01*
Y-23858D01*
Y-23804D01*
X343993D01*
Y-23750D01*
X344047D01*
Y-23696D01*
Y-23642D01*
X344101D01*
Y-23588D01*
Y-23534D01*
X344155D01*
Y-23480D01*
Y-23426D01*
X344209D01*
Y-23371D01*
Y-23317D01*
X344263D01*
Y-23263D01*
Y-23209D01*
X344317D01*
Y-23155D01*
X344371D01*
Y-23101D01*
Y-23047D01*
X344425D01*
Y-22993D01*
Y-22939D01*
X344479D01*
Y-22885D01*
Y-22831D01*
X344533D01*
Y-22777D01*
X344587D01*
Y-22723D01*
Y-22669D01*
X344642D01*
Y-22615D01*
Y-22561D01*
X344696D01*
Y-22506D01*
X344750D01*
Y-22452D01*
Y-22398D01*
X344804D01*
Y-22344D01*
Y-22290D01*
X344858D01*
Y-22236D01*
X344912D01*
Y-22182D01*
Y-22128D01*
X344966D01*
Y-22074D01*
X345020D01*
Y-22020D01*
Y-21966D01*
X345074D01*
Y-21912D01*
X345128D01*
Y-21858D01*
Y-21804D01*
X345182D01*
Y-21750D01*
X345236D01*
Y-21696D01*
Y-21642D01*
X345290D01*
Y-21587D01*
X345344D01*
Y-21533D01*
Y-21479D01*
X345398D01*
Y-21425D01*
X345452D01*
Y-21371D01*
X345507D01*
Y-21317D01*
Y-21263D01*
X345561D01*
Y-21209D01*
X345615D01*
Y-21155D01*
Y-21101D01*
X345669D01*
Y-21047D01*
X345723D01*
Y-20993D01*
X345777D01*
Y-20939D01*
Y-20885D01*
X345831D01*
Y-20831D01*
X345885D01*
Y-20776D01*
X345939D01*
Y-20722D01*
Y-20668D01*
X345993D01*
Y-20614D01*
X346047D01*
Y-20560D01*
X346101D01*
Y-20506D01*
X346155D01*
Y-20452D01*
Y-20398D01*
X346209D01*
Y-20344D01*
X346263D01*
Y-20290D01*
X346318D01*
Y-20236D01*
X346372D01*
Y-20182D01*
Y-20128D01*
X346426D01*
Y-20074D01*
X346480D01*
Y-20020D01*
X346534D01*
Y-19966D01*
X346588D01*
Y-19911D01*
X346642D01*
Y-19858D01*
X346696D01*
Y-19803D01*
Y-19749D01*
X346750D01*
Y-19695D01*
X346804D01*
Y-19641D01*
X346858D01*
Y-19587D01*
X346912D01*
Y-19533D01*
X346966D01*
Y-19479D01*
X347020D01*
Y-19425D01*
X347074D01*
Y-19371D01*
X347128D01*
Y-19317D01*
X347182D01*
Y-19263D01*
Y-19209D01*
X347236D01*
Y-19155D01*
X347291D01*
Y-19101D01*
X347345D01*
Y-19047D01*
X347399D01*
Y-18993D01*
X347453D01*
Y-18938D01*
X347507D01*
Y-18884D01*
X347561D01*
Y-18830D01*
X347615D01*
Y-18776D01*
X347669D01*
Y-18722D01*
X347723D01*
Y-18668D01*
X347777D01*
Y-18614D01*
X347831D01*
Y-18560D01*
X347885D01*
Y-18506D01*
X347939D01*
Y-18452D01*
X347993D01*
Y-18398D01*
X348047D01*
Y-18344D01*
X348101D01*
Y-18290D01*
X348210D01*
Y-18236D01*
X348264D01*
Y-18181D01*
X348318D01*
Y-18127D01*
X348372D01*
Y-18073D01*
X348426D01*
Y-18019D01*
X348480D01*
Y-17965D01*
X348534D01*
Y-17911D01*
X348588D01*
Y-17857D01*
X348642D01*
Y-17803D01*
X348750D01*
Y-17749D01*
X348804D01*
Y-17695D01*
X348858D01*
Y-17641D01*
X348913D01*
Y-17587D01*
X348967D01*
Y-17533D01*
X349021D01*
Y-17479D01*
X349129D01*
Y-17425D01*
X349183D01*
Y-17371D01*
X349237D01*
Y-17317D01*
X349291D01*
Y-17263D01*
X349399D01*
Y-17208D01*
X349453D01*
Y-17154D01*
X349507D01*
Y-17100D01*
X349561D01*
Y-17046D01*
X349669D01*
Y-16992D01*
X349723D01*
Y-16938D01*
X349778D01*
Y-16884D01*
X349886D01*
Y-16830D01*
X349940D01*
Y-16776D01*
X349994D01*
Y-16722D01*
X350102D01*
Y-16668D01*
X350156D01*
Y-16614D01*
X350264D01*
Y-16560D01*
X350318D01*
Y-16506D01*
X350372D01*
Y-16452D01*
X350480D01*
Y-16398D01*
X350534D01*
Y-16343D01*
X350642D01*
Y-16289D01*
X350696D01*
Y-16235D01*
X350805D01*
Y-16181D01*
X350859D01*
Y-16127D01*
X350967D01*
Y-16073D01*
X351021D01*
Y-16019D01*
X351129D01*
Y-15965D01*
X351183D01*
Y-15911D01*
X351291D01*
Y-15857D01*
X351399D01*
Y-15803D01*
X351453D01*
Y-15749D01*
X351561D01*
Y-15695D01*
X351670D01*
Y-15641D01*
X351724D01*
Y-15587D01*
X351832D01*
Y-15532D01*
X351940D01*
Y-15478D01*
X352048D01*
Y-15424D01*
X352102D01*
Y-15370D01*
X352210D01*
Y-15316D01*
X352318D01*
Y-15262D01*
X352427D01*
Y-15208D01*
X352535D01*
Y-15154D01*
X352643D01*
Y-15100D01*
X352751D01*
Y-15046D01*
X352859D01*
Y-14992D01*
X352967D01*
Y-14938D01*
X353021D01*
Y-14884D01*
X353129D01*
Y-14830D01*
X353292D01*
Y-14776D01*
X353400D01*
Y-14722D01*
X353508D01*
Y-14668D01*
X353616D01*
Y-14614D01*
X353724D01*
Y-14559D01*
X353886D01*
Y-14505D01*
X353994D01*
Y-14451D01*
X354102D01*
Y-14397D01*
X354265D01*
Y-14343D01*
X354373D01*
Y-14289D01*
X354535D01*
Y-14235D01*
X354643D01*
Y-14181D01*
X354805D01*
Y-14127D01*
X354913D01*
Y-14073D01*
X355076D01*
Y-14019D01*
X355238D01*
Y-13965D01*
X355400D01*
Y-13911D01*
X355562D01*
Y-13857D01*
X355724D01*
Y-13803D01*
X355887D01*
Y-13748D01*
X356049D01*
Y-13694D01*
X356211D01*
Y-13640D01*
X356427D01*
Y-13586D01*
X356589D01*
Y-13532D01*
X356805D01*
Y-13478D01*
X357022D01*
Y-13424D01*
X357238D01*
Y-13370D01*
X357454D01*
Y-13316D01*
X357725D01*
Y-13262D01*
X357995D01*
Y-13208D01*
X358265D01*
Y-13154D01*
X358590D01*
Y-13100D01*
X358914D01*
Y-13046D01*
X359238D01*
Y-12992D01*
X359725D01*
Y-12937D01*
X360320D01*
Y-12883D01*
X361185D01*
Y-12829D01*
X361239D01*
Y-12883D01*
X361293D01*
Y-12829D01*
X362644D01*
Y-12883D01*
X363617D01*
Y-12937D01*
X364212D01*
Y-12992D01*
X364645D01*
Y-13046D01*
X365023D01*
Y-13100D01*
X365347D01*
Y-13154D01*
X365726D01*
Y-13208D01*
X365942D01*
Y-13262D01*
X366212D01*
Y-13316D01*
X366483D01*
Y-13370D01*
X366699D01*
Y-13424D01*
X366915D01*
Y-13478D01*
X367131D01*
Y-13532D01*
X367348D01*
Y-13586D01*
X367510D01*
Y-13640D01*
X367726D01*
Y-13694D01*
X367888D01*
Y-13748D01*
X368050D01*
Y-13803D01*
X368213D01*
Y-13857D01*
X368429D01*
Y-13911D01*
X368537D01*
Y-13965D01*
X368699D01*
Y-14019D01*
X368861D01*
Y-14073D01*
X369023D01*
Y-14127D01*
X369132D01*
Y-14181D01*
X369294D01*
Y-14235D01*
X369456D01*
Y-14289D01*
X369564D01*
Y-14343D01*
X369726D01*
Y-14397D01*
X369834D01*
Y-14451D01*
X369943D01*
Y-14505D01*
X370105D01*
Y-14559D01*
X370213D01*
Y-14614D01*
X370321D01*
Y-14668D01*
X370429D01*
Y-14722D01*
X370537D01*
Y-14776D01*
X370645D01*
Y-14830D01*
X370808D01*
Y-14884D01*
X370916D01*
Y-14938D01*
X371024D01*
Y-14992D01*
X371132D01*
Y-15046D01*
X371240D01*
Y-15100D01*
X371294D01*
Y-15154D01*
X371402D01*
Y-15208D01*
X371510D01*
Y-15262D01*
X371619D01*
Y-15316D01*
X371727D01*
Y-15370D01*
X371835D01*
Y-15424D01*
X371943D01*
Y-15478D01*
X371997D01*
Y-15532D01*
X372105D01*
Y-15587D01*
X372213D01*
Y-15641D01*
X372267D01*
Y-15695D01*
X372375D01*
Y-15749D01*
X372483D01*
Y-15803D01*
X372538D01*
Y-15857D01*
X372646D01*
Y-15911D01*
X372754D01*
Y-15965D01*
X372808D01*
Y-16019D01*
X372916D01*
Y-16073D01*
X372970D01*
Y-16127D01*
X373078D01*
Y-16181D01*
X373132D01*
Y-16235D01*
X373240D01*
Y-16289D01*
X373294D01*
Y-16343D01*
X373403D01*
Y-16398D01*
X373457D01*
Y-16452D01*
X373565D01*
Y-16506D01*
X373619D01*
Y-16560D01*
X373727D01*
Y-16614D01*
X373781D01*
Y-16668D01*
X373835D01*
Y-16722D01*
X373943D01*
Y-16776D01*
X373997D01*
Y-16830D01*
X374051D01*
Y-16884D01*
X374159D01*
Y-16938D01*
X374214D01*
Y-16992D01*
X374268D01*
Y-17046D01*
X374376D01*
Y-17100D01*
X374430D01*
Y-17154D01*
X374484D01*
Y-17208D01*
X374538D01*
Y-17263D01*
X374646D01*
Y-17317D01*
X374700D01*
Y-17371D01*
X374754D01*
Y-17425D01*
X374808D01*
Y-17479D01*
X374916D01*
Y-17533D01*
X374970D01*
Y-17587D01*
X375024D01*
Y-17641D01*
X375079D01*
Y-17695D01*
X375132D01*
Y-17749D01*
X375241D01*
Y-17803D01*
X375295D01*
Y-17857D01*
X375349D01*
Y-17911D01*
X375403D01*
Y-17965D01*
X375457D01*
Y-18019D01*
X375511D01*
Y-18073D01*
X375565D01*
Y-18127D01*
X375619D01*
Y-18181D01*
X375673D01*
Y-18236D01*
X375781D01*
Y-18290D01*
X375835D01*
Y-18344D01*
X375889D01*
Y-18398D01*
X375943D01*
Y-18452D01*
X375997D01*
Y-18506D01*
X376052D01*
Y-18560D01*
X376106D01*
Y-18614D01*
X376160D01*
Y-18668D01*
X376214D01*
Y-18722D01*
X376268D01*
Y-18776D01*
X376322D01*
Y-18830D01*
X376376D01*
Y-18884D01*
X376430D01*
Y-18938D01*
X376484D01*
Y-18993D01*
X376538D01*
Y-19047D01*
X376592D01*
Y-19101D01*
X376646D01*
Y-19155D01*
X376700D01*
Y-19209D01*
X376754D01*
Y-19263D01*
X376809D01*
Y-19317D01*
X376863D01*
Y-19371D01*
Y-19425D01*
X376917D01*
Y-19479D01*
X376971D01*
Y-19533D01*
X377025D01*
Y-19587D01*
X377079D01*
Y-19641D01*
X377133D01*
Y-19695D01*
X377187D01*
Y-19749D01*
X377241D01*
Y-19803D01*
X377295D01*
Y-19858D01*
Y-19911D01*
X377349D01*
Y-19966D01*
X377403D01*
Y-20020D01*
X378268D01*
Y-19966D01*
X378214D01*
Y-19911D01*
X378160D01*
Y-19858D01*
X378106D01*
Y-19803D01*
Y-19749D01*
X378052D01*
Y-19695D01*
X377998D01*
Y-19641D01*
X377944D01*
Y-19587D01*
X377890D01*
Y-19533D01*
X377836D01*
Y-19479D01*
Y-19425D01*
X377782D01*
Y-19371D01*
X377728D01*
Y-19317D01*
X377674D01*
Y-19263D01*
X377619D01*
Y-19209D01*
X377565D01*
Y-19155D01*
X377511D01*
Y-19101D01*
X377457D01*
Y-19047D01*
X377403D01*
Y-18993D01*
Y-18938D01*
X377349D01*
Y-18884D01*
X377295D01*
Y-18830D01*
X377241D01*
Y-18776D01*
X377187D01*
Y-18722D01*
X377133D01*
Y-18668D01*
X377079D01*
Y-18614D01*
X377025D01*
Y-18560D01*
X376971D01*
Y-18506D01*
X376917D01*
Y-18452D01*
X376863D01*
Y-18398D01*
X376809D01*
Y-18344D01*
X376754D01*
Y-18290D01*
X376700D01*
Y-18236D01*
X376646D01*
Y-18181D01*
X376592D01*
Y-18127D01*
X376538D01*
Y-18073D01*
X376484D01*
Y-18019D01*
X376430D01*
Y-17965D01*
X376376D01*
Y-17911D01*
X376322D01*
Y-17857D01*
X376268D01*
Y-17803D01*
X376214D01*
Y-17749D01*
X376160D01*
Y-17695D01*
X376106D01*
Y-17641D01*
X375997D01*
Y-17587D01*
X375943D01*
Y-17533D01*
X375889D01*
Y-17479D01*
X375835D01*
Y-17425D01*
X375781D01*
Y-17371D01*
X375727D01*
Y-17317D01*
X375673D01*
Y-17263D01*
X375619D01*
Y-17208D01*
X375511D01*
Y-17154D01*
X375457D01*
Y-17100D01*
X375403D01*
Y-17046D01*
X375349D01*
Y-16992D01*
X375295D01*
Y-16938D01*
X375187D01*
Y-16884D01*
X375132D01*
Y-16830D01*
X375079D01*
Y-16776D01*
X375024D01*
Y-16722D01*
X374916D01*
Y-16668D01*
X374862D01*
Y-16614D01*
X374808D01*
Y-16560D01*
X374754D01*
Y-16506D01*
X374646D01*
Y-16452D01*
X374592D01*
Y-16398D01*
X374538D01*
Y-16343D01*
X374430D01*
Y-16289D01*
X374376D01*
Y-16235D01*
X374322D01*
Y-16181D01*
X374214D01*
Y-16127D01*
X374159D01*
Y-16073D01*
X374051D01*
Y-16019D01*
X373997D01*
Y-15965D01*
X373943D01*
Y-15911D01*
X373835D01*
Y-15857D01*
X373781D01*
Y-15803D01*
X373673D01*
Y-15749D01*
X373619D01*
Y-15695D01*
X373511D01*
Y-15641D01*
X373457D01*
Y-15587D01*
X373348D01*
Y-15532D01*
X373294D01*
Y-15478D01*
X373186D01*
Y-15424D01*
X373132D01*
Y-15370D01*
X373024D01*
Y-15316D01*
X372916D01*
Y-15262D01*
X372862D01*
Y-15208D01*
X372754D01*
Y-15154D01*
X372646D01*
Y-15100D01*
X372592D01*
Y-15046D01*
X372483D01*
Y-14992D01*
X372375D01*
Y-14938D01*
X372321D01*
Y-14884D01*
X372213D01*
Y-14830D01*
X372105D01*
Y-14776D01*
X371997D01*
Y-14722D01*
X371889D01*
Y-14668D01*
X371835D01*
Y-14614D01*
X371727D01*
Y-14559D01*
X371619D01*
Y-14505D01*
X371510D01*
Y-14451D01*
X371402D01*
Y-14397D01*
X371294D01*
Y-14343D01*
X371186D01*
Y-14289D01*
X371078D01*
Y-14235D01*
X370970D01*
Y-14181D01*
X370862D01*
Y-14127D01*
X370700D01*
Y-14073D01*
X370591D01*
Y-14019D01*
X370483D01*
Y-13965D01*
X370375D01*
Y-13911D01*
X370213D01*
Y-13857D01*
X370105D01*
Y-13803D01*
X369997D01*
Y-13748D01*
X369834D01*
Y-13694D01*
X369726D01*
Y-13640D01*
X369564D01*
Y-13586D01*
X369456D01*
Y-13532D01*
X369294D01*
Y-13478D01*
X369132D01*
Y-13424D01*
X368969D01*
Y-13370D01*
X368861D01*
Y-13316D01*
X368699D01*
Y-13262D01*
X368537D01*
Y-13208D01*
X368375D01*
Y-13154D01*
X368159D01*
Y-13100D01*
X367996D01*
Y-13046D01*
X367834D01*
Y-12992D01*
X367618D01*
Y-12937D01*
X367456D01*
Y-12883D01*
X367239D01*
Y-12829D01*
X367023D01*
Y-12775D01*
X366807D01*
Y-12721D01*
X366591D01*
Y-12667D01*
X366320D01*
Y-12613D01*
X366050D01*
Y-12559D01*
X365780D01*
Y-12505D01*
X365456D01*
Y-12451D01*
X365077D01*
Y-12397D01*
X364753D01*
Y-12343D01*
X364320D01*
Y-12289D01*
X363779D01*
Y-12235D01*
X362969D01*
Y-12181D01*
D02*
G37*
G36*
X386972Y-20885D02*
X378647D01*
Y-20939D01*
X378592D01*
Y-20885D01*
X378484D01*
Y-20939D01*
X378376D01*
Y-20993D01*
X378322D01*
Y-21047D01*
X378268D01*
Y-21101D01*
Y-21155D01*
Y-21209D01*
X378214D01*
Y-21263D01*
Y-21317D01*
Y-21371D01*
Y-21425D01*
Y-21479D01*
Y-21533D01*
Y-21587D01*
Y-21642D01*
Y-21696D01*
Y-21750D01*
Y-21804D01*
Y-21858D01*
Y-21912D01*
Y-21966D01*
Y-22020D01*
Y-22074D01*
Y-22128D01*
Y-22182D01*
Y-22236D01*
Y-22290D01*
Y-22344D01*
Y-22398D01*
Y-22452D01*
Y-22506D01*
Y-22561D01*
Y-22615D01*
Y-22669D01*
Y-22723D01*
Y-22777D01*
Y-22831D01*
Y-22885D01*
Y-22939D01*
Y-22993D01*
Y-23047D01*
Y-23101D01*
Y-23155D01*
Y-23209D01*
Y-23263D01*
Y-23317D01*
Y-23371D01*
Y-23426D01*
Y-23480D01*
X378268D01*
Y-23534D01*
Y-23588D01*
Y-23642D01*
X378322D01*
Y-23696D01*
X378376D01*
Y-23750D01*
X378538D01*
Y-23804D01*
X381133D01*
Y-23858D01*
X381188D01*
Y-23912D01*
X381242D01*
Y-23966D01*
Y-24020D01*
Y-24074D01*
Y-24128D01*
Y-24182D01*
Y-24237D01*
Y-24291D01*
Y-24345D01*
Y-24399D01*
Y-24453D01*
Y-24507D01*
Y-24561D01*
Y-24615D01*
Y-24669D01*
Y-24723D01*
Y-24777D01*
Y-24831D01*
Y-24885D01*
Y-24939D01*
Y-24993D01*
Y-25047D01*
Y-25102D01*
Y-25155D01*
Y-25210D01*
Y-25264D01*
Y-25318D01*
Y-25372D01*
Y-25426D01*
Y-25480D01*
Y-25534D01*
Y-25588D01*
Y-25642D01*
Y-25696D01*
Y-25750D01*
Y-25804D01*
Y-25858D01*
Y-25912D01*
Y-25967D01*
Y-26021D01*
Y-26075D01*
Y-26129D01*
Y-26183D01*
Y-26237D01*
Y-26291D01*
Y-26345D01*
Y-26399D01*
Y-26453D01*
Y-26507D01*
Y-26561D01*
Y-26615D01*
Y-26669D01*
Y-26723D01*
Y-26777D01*
Y-26831D01*
Y-26886D01*
Y-26940D01*
Y-26994D01*
Y-27048D01*
Y-27102D01*
Y-27156D01*
Y-27210D01*
Y-27264D01*
Y-27318D01*
Y-27372D01*
Y-27426D01*
Y-27480D01*
Y-27534D01*
Y-27588D01*
Y-27642D01*
Y-27696D01*
Y-27751D01*
Y-27805D01*
Y-27859D01*
Y-27913D01*
Y-27967D01*
Y-28021D01*
Y-28075D01*
Y-28129D01*
Y-28183D01*
Y-28237D01*
Y-28291D01*
Y-28345D01*
Y-28399D01*
Y-28453D01*
Y-28507D01*
Y-28561D01*
Y-28615D01*
Y-28670D01*
Y-28724D01*
Y-28778D01*
Y-28832D01*
Y-28886D01*
Y-28940D01*
Y-28994D01*
Y-29048D01*
Y-29102D01*
Y-29156D01*
Y-29210D01*
Y-29264D01*
Y-29318D01*
Y-29372D01*
Y-29426D01*
Y-29480D01*
Y-29535D01*
Y-29589D01*
Y-29643D01*
Y-29697D01*
Y-29751D01*
Y-29805D01*
Y-29859D01*
Y-29913D01*
Y-29967D01*
Y-30021D01*
Y-30075D01*
Y-30129D01*
Y-30183D01*
Y-30237D01*
Y-30291D01*
Y-30345D01*
Y-30400D01*
Y-30454D01*
Y-30508D01*
Y-30562D01*
Y-30616D01*
Y-30670D01*
Y-30724D01*
Y-30778D01*
Y-30832D01*
Y-30886D01*
Y-30940D01*
Y-30994D01*
Y-31048D01*
Y-31102D01*
Y-31156D01*
Y-31211D01*
Y-31265D01*
Y-31319D01*
Y-31373D01*
Y-31427D01*
Y-31481D01*
Y-31535D01*
Y-31589D01*
Y-31643D01*
Y-31697D01*
Y-31751D01*
Y-31805D01*
Y-31859D01*
Y-31913D01*
Y-31967D01*
Y-32021D01*
Y-32076D01*
Y-32129D01*
Y-32184D01*
Y-32238D01*
Y-32292D01*
Y-32346D01*
Y-32400D01*
X381296D01*
Y-32454D01*
Y-32508D01*
Y-32562D01*
X381350D01*
Y-32616D01*
X381404D01*
Y-32670D01*
X384053D01*
Y-32616D01*
X384107D01*
Y-32562D01*
X384161D01*
Y-32508D01*
X384215D01*
Y-32454D01*
Y-32400D01*
Y-32346D01*
Y-32292D01*
Y-32238D01*
Y-32184D01*
Y-32129D01*
Y-32076D01*
Y-32021D01*
Y-31967D01*
Y-31913D01*
Y-31859D01*
Y-31805D01*
Y-31751D01*
Y-31697D01*
Y-31643D01*
Y-31589D01*
Y-31535D01*
Y-31481D01*
Y-31427D01*
Y-31373D01*
Y-31319D01*
Y-31265D01*
Y-31211D01*
Y-31156D01*
Y-31102D01*
Y-31048D01*
Y-30994D01*
Y-30940D01*
Y-30886D01*
Y-30832D01*
Y-30778D01*
Y-30724D01*
Y-30670D01*
Y-30616D01*
Y-30562D01*
Y-30508D01*
Y-30454D01*
Y-30400D01*
Y-30345D01*
Y-30291D01*
Y-30237D01*
Y-30183D01*
Y-30129D01*
Y-30075D01*
Y-30021D01*
Y-29967D01*
Y-29913D01*
Y-29859D01*
Y-29805D01*
Y-29751D01*
Y-29697D01*
Y-29643D01*
Y-29589D01*
Y-29535D01*
Y-29480D01*
Y-29426D01*
Y-29372D01*
Y-29318D01*
Y-29264D01*
Y-29210D01*
Y-29156D01*
Y-29102D01*
Y-29048D01*
Y-28994D01*
Y-28940D01*
Y-28886D01*
Y-28832D01*
Y-28778D01*
Y-28724D01*
Y-28670D01*
Y-28615D01*
Y-28561D01*
Y-28507D01*
Y-28453D01*
Y-28399D01*
Y-28345D01*
Y-28291D01*
Y-28237D01*
Y-28183D01*
Y-28129D01*
Y-28075D01*
Y-28021D01*
Y-27967D01*
Y-27913D01*
Y-27859D01*
Y-27805D01*
Y-27751D01*
Y-27696D01*
Y-27642D01*
Y-27588D01*
Y-27534D01*
Y-27480D01*
Y-27426D01*
Y-27372D01*
Y-27318D01*
Y-27264D01*
Y-27210D01*
Y-27156D01*
Y-27102D01*
Y-27048D01*
Y-26994D01*
Y-26940D01*
Y-26886D01*
Y-26831D01*
Y-26777D01*
Y-26723D01*
Y-26669D01*
Y-26615D01*
Y-26561D01*
Y-26507D01*
Y-26453D01*
Y-26399D01*
Y-26345D01*
Y-26291D01*
Y-26237D01*
Y-26183D01*
Y-26129D01*
Y-26075D01*
Y-26021D01*
Y-25967D01*
Y-25912D01*
Y-25858D01*
Y-25804D01*
Y-25750D01*
Y-25696D01*
Y-25642D01*
Y-25588D01*
Y-25534D01*
Y-25480D01*
Y-25426D01*
Y-25372D01*
Y-25318D01*
Y-25264D01*
Y-25210D01*
Y-25155D01*
Y-25102D01*
Y-25047D01*
Y-24993D01*
Y-24939D01*
Y-24885D01*
Y-24831D01*
Y-24777D01*
Y-24723D01*
Y-24669D01*
Y-24615D01*
Y-24561D01*
Y-24507D01*
Y-24453D01*
Y-24399D01*
Y-24345D01*
Y-24291D01*
Y-24237D01*
Y-24182D01*
Y-24128D01*
Y-24074D01*
Y-24020D01*
X384269D01*
Y-23966D01*
Y-23912D01*
X384323D01*
Y-23858D01*
X384377D01*
Y-23804D01*
X386972D01*
Y-23750D01*
X387080D01*
Y-23696D01*
X387134D01*
Y-23642D01*
X387188D01*
Y-23588D01*
X387242D01*
Y-23534D01*
Y-23480D01*
Y-23426D01*
Y-23371D01*
Y-23317D01*
Y-23263D01*
Y-23209D01*
Y-23155D01*
Y-23101D01*
Y-23047D01*
Y-22993D01*
Y-22939D01*
Y-22885D01*
Y-22831D01*
Y-22777D01*
Y-22723D01*
Y-22669D01*
Y-22615D01*
Y-22561D01*
Y-22506D01*
Y-22452D01*
Y-22398D01*
Y-22344D01*
Y-22290D01*
Y-22236D01*
Y-22182D01*
Y-22128D01*
Y-22074D01*
Y-22020D01*
Y-21966D01*
Y-21912D01*
Y-21858D01*
Y-21804D01*
Y-21750D01*
Y-21696D01*
Y-21642D01*
Y-21587D01*
Y-21533D01*
Y-21479D01*
Y-21425D01*
Y-21371D01*
Y-21317D01*
Y-21263D01*
Y-21209D01*
Y-21155D01*
Y-21101D01*
X387188D01*
Y-21047D01*
Y-20993D01*
X387134D01*
Y-20939D01*
X386972D01*
Y-20885D01*
D02*
G37*
G36*
X357346D02*
X351021D01*
Y-20939D01*
X350967D01*
Y-20885D01*
X350805D01*
Y-20939D01*
X350696D01*
Y-20993D01*
X350642D01*
Y-21047D01*
X350588D01*
Y-21101D01*
Y-21155D01*
X350534D01*
Y-21209D01*
Y-21263D01*
Y-21317D01*
Y-21371D01*
Y-21425D01*
Y-21479D01*
Y-21533D01*
Y-21587D01*
Y-21642D01*
Y-21696D01*
Y-21750D01*
Y-21804D01*
Y-21858D01*
Y-21912D01*
Y-21966D01*
Y-22020D01*
Y-22074D01*
Y-22128D01*
Y-22182D01*
Y-22236D01*
Y-22290D01*
Y-22344D01*
Y-22398D01*
Y-22452D01*
Y-22506D01*
Y-22561D01*
Y-22615D01*
Y-22669D01*
Y-22723D01*
Y-22777D01*
Y-22831D01*
Y-22885D01*
Y-22939D01*
Y-22993D01*
Y-23047D01*
Y-23101D01*
Y-23155D01*
Y-23209D01*
Y-23263D01*
Y-23317D01*
Y-23371D01*
Y-23426D01*
Y-23480D01*
X350588D01*
Y-23534D01*
X350642D01*
Y-23588D01*
X350696D01*
Y-23642D01*
X356535D01*
Y-23696D01*
X356589D01*
Y-23750D01*
Y-23804D01*
Y-23858D01*
Y-23912D01*
Y-23966D01*
Y-24020D01*
Y-24074D01*
Y-24128D01*
Y-24182D01*
Y-24237D01*
Y-24291D01*
Y-24345D01*
Y-24399D01*
Y-24453D01*
Y-24507D01*
Y-24561D01*
Y-24615D01*
Y-24669D01*
Y-24723D01*
Y-24777D01*
Y-24831D01*
Y-24885D01*
Y-24939D01*
Y-24993D01*
Y-25047D01*
Y-25102D01*
Y-25155D01*
Y-25210D01*
Y-25264D01*
Y-25318D01*
Y-25372D01*
Y-25426D01*
Y-25480D01*
Y-25534D01*
Y-25588D01*
X356535D01*
Y-25642D01*
X351561D01*
Y-25696D01*
X351453D01*
Y-25750D01*
Y-25804D01*
X351399D01*
Y-25858D01*
Y-25912D01*
Y-25967D01*
Y-26021D01*
Y-26075D01*
Y-26129D01*
Y-26183D01*
Y-26237D01*
Y-26291D01*
Y-26345D01*
Y-26399D01*
Y-26453D01*
Y-26507D01*
Y-26561D01*
Y-26615D01*
Y-26669D01*
Y-26723D01*
Y-26777D01*
Y-26831D01*
Y-26886D01*
Y-26940D01*
Y-26994D01*
Y-27048D01*
Y-27102D01*
Y-27156D01*
Y-27210D01*
Y-27264D01*
Y-27318D01*
Y-27372D01*
Y-27426D01*
Y-27480D01*
Y-27534D01*
Y-27588D01*
Y-27642D01*
Y-27696D01*
Y-27751D01*
Y-27805D01*
X351453D01*
Y-27859D01*
Y-27913D01*
X351561D01*
Y-27967D01*
X356535D01*
Y-28021D01*
X356589D01*
Y-28075D01*
Y-28129D01*
Y-28183D01*
Y-28237D01*
Y-28291D01*
Y-28345D01*
Y-28399D01*
Y-28453D01*
Y-28507D01*
Y-28561D01*
Y-28615D01*
Y-28670D01*
Y-28724D01*
Y-28778D01*
Y-28832D01*
Y-28886D01*
Y-28940D01*
Y-28994D01*
Y-29048D01*
Y-29102D01*
Y-29156D01*
Y-29210D01*
Y-29264D01*
Y-29318D01*
Y-29372D01*
Y-29426D01*
Y-29480D01*
Y-29535D01*
Y-29589D01*
Y-29643D01*
Y-29697D01*
Y-29751D01*
Y-29805D01*
Y-29859D01*
X356535D01*
Y-29913D01*
X350751D01*
Y-29967D01*
X350642D01*
Y-30021D01*
X350588D01*
Y-30075D01*
Y-30129D01*
X350534D01*
Y-30183D01*
Y-30237D01*
Y-30291D01*
Y-30345D01*
Y-30400D01*
Y-30454D01*
Y-30508D01*
Y-30562D01*
Y-30616D01*
Y-30670D01*
Y-30724D01*
Y-30778D01*
Y-30832D01*
Y-30886D01*
Y-30940D01*
Y-30994D01*
Y-31048D01*
Y-31102D01*
Y-31156D01*
Y-31211D01*
Y-31265D01*
Y-31319D01*
Y-31373D01*
Y-31427D01*
Y-31481D01*
Y-31535D01*
Y-31589D01*
Y-31643D01*
Y-31697D01*
Y-31751D01*
Y-31805D01*
Y-31859D01*
Y-31913D01*
Y-31967D01*
Y-32021D01*
Y-32076D01*
Y-32129D01*
Y-32184D01*
Y-32238D01*
Y-32292D01*
Y-32346D01*
Y-32400D01*
Y-32454D01*
X350588D01*
Y-32508D01*
Y-32562D01*
X350642D01*
Y-32616D01*
X350696D01*
Y-32670D01*
X357562D01*
Y-32616D01*
X357779D01*
Y-32562D01*
X357887D01*
Y-32508D01*
X357941D01*
Y-32454D01*
X357995D01*
Y-32400D01*
X358049D01*
Y-32346D01*
X358103D01*
Y-32292D01*
X358157D01*
Y-32238D01*
X358211D01*
Y-32184D01*
X358265D01*
Y-32129D01*
X358319D01*
Y-32076D01*
X358373D01*
Y-32021D01*
X358427D01*
Y-31967D01*
X358481D01*
Y-31913D01*
X358536D01*
Y-31859D01*
X358590D01*
Y-31805D01*
X358644D01*
Y-31751D01*
X358698D01*
Y-31697D01*
X358752D01*
Y-31643D01*
X358806D01*
Y-31589D01*
X358860D01*
Y-31535D01*
X358914D01*
Y-31481D01*
X358968D01*
Y-31427D01*
X359022D01*
Y-31373D01*
X359076D01*
Y-31319D01*
X359130D01*
Y-31265D01*
X359184D01*
Y-31211D01*
X359238D01*
Y-31156D01*
X359292D01*
Y-31102D01*
X359346D01*
Y-31048D01*
X359401D01*
Y-30994D01*
Y-30940D01*
X359455D01*
Y-30886D01*
Y-30832D01*
X359509D01*
Y-30778D01*
Y-30724D01*
Y-30670D01*
Y-30616D01*
Y-30562D01*
X359563D01*
Y-30508D01*
Y-30454D01*
Y-30400D01*
Y-30345D01*
Y-30291D01*
Y-30237D01*
Y-30183D01*
Y-30129D01*
Y-30075D01*
Y-30021D01*
Y-29967D01*
Y-29913D01*
Y-29859D01*
Y-29805D01*
Y-29751D01*
Y-29697D01*
Y-29643D01*
Y-29589D01*
Y-29535D01*
Y-29480D01*
Y-29426D01*
Y-29372D01*
Y-29318D01*
Y-29264D01*
Y-29210D01*
Y-29156D01*
Y-29102D01*
Y-29048D01*
Y-28994D01*
Y-28940D01*
Y-28886D01*
Y-28832D01*
Y-28778D01*
Y-28724D01*
Y-28670D01*
Y-28615D01*
Y-28561D01*
Y-28507D01*
Y-28453D01*
Y-28399D01*
Y-28345D01*
Y-28291D01*
Y-28237D01*
Y-28183D01*
Y-28129D01*
Y-28075D01*
Y-28021D01*
Y-27967D01*
Y-27913D01*
Y-27859D01*
Y-27805D01*
Y-27751D01*
Y-27696D01*
Y-27642D01*
Y-27588D01*
Y-27534D01*
Y-27480D01*
Y-27426D01*
Y-27372D01*
Y-27318D01*
Y-27264D01*
Y-27210D01*
Y-27156D01*
Y-27102D01*
Y-27048D01*
Y-26994D01*
Y-26940D01*
Y-26886D01*
Y-26831D01*
Y-26777D01*
Y-26723D01*
Y-26669D01*
Y-26615D01*
Y-26561D01*
Y-26507D01*
Y-26453D01*
Y-26399D01*
Y-26345D01*
Y-26291D01*
Y-26237D01*
Y-26183D01*
Y-26129D01*
Y-26075D01*
Y-26021D01*
Y-25967D01*
Y-25912D01*
Y-25858D01*
Y-25804D01*
Y-25750D01*
Y-25696D01*
Y-25642D01*
Y-25588D01*
Y-25534D01*
Y-25480D01*
Y-25426D01*
Y-25372D01*
Y-25318D01*
Y-25264D01*
Y-25210D01*
Y-25155D01*
Y-25102D01*
Y-25047D01*
Y-24993D01*
Y-24939D01*
Y-24885D01*
Y-24831D01*
Y-24777D01*
Y-24723D01*
Y-24669D01*
Y-24615D01*
Y-24561D01*
Y-24507D01*
Y-24453D01*
Y-24399D01*
Y-24345D01*
Y-24291D01*
Y-24237D01*
Y-24182D01*
Y-24128D01*
Y-24074D01*
Y-24020D01*
Y-23966D01*
Y-23912D01*
Y-23858D01*
Y-23804D01*
Y-23750D01*
Y-23696D01*
Y-23642D01*
Y-23588D01*
Y-23534D01*
Y-23480D01*
Y-23426D01*
Y-23371D01*
Y-23317D01*
Y-23263D01*
Y-23209D01*
Y-23155D01*
Y-23101D01*
Y-23047D01*
X359509D01*
Y-22993D01*
Y-22939D01*
Y-22885D01*
Y-22831D01*
Y-22777D01*
X359455D01*
Y-22723D01*
Y-22669D01*
Y-22615D01*
X359401D01*
Y-22561D01*
X359346D01*
Y-22506D01*
X359292D01*
Y-22452D01*
X359238D01*
Y-22398D01*
X359184D01*
Y-22344D01*
X359130D01*
Y-22290D01*
X359076D01*
Y-22236D01*
X359022D01*
Y-22182D01*
X358968D01*
Y-22128D01*
X358914D01*
Y-22074D01*
X358860D01*
Y-22020D01*
X358806D01*
Y-21966D01*
X358752D01*
Y-21912D01*
X358698D01*
Y-21858D01*
X358644D01*
Y-21804D01*
X358590D01*
Y-21750D01*
X358536D01*
Y-21696D01*
X358481D01*
Y-21642D01*
X358427D01*
Y-21587D01*
X358373D01*
Y-21533D01*
X358319D01*
Y-21479D01*
X358265D01*
Y-21425D01*
X358211D01*
Y-21371D01*
X358157D01*
Y-21317D01*
X358103D01*
Y-21263D01*
X358049D01*
Y-21209D01*
X357995D01*
Y-21155D01*
X357941D01*
Y-21101D01*
X357887D01*
Y-21047D01*
X357779D01*
Y-20993D01*
X357616D01*
Y-20939D01*
X357346D01*
Y-20885D01*
D02*
G37*
G36*
X377295D02*
X374808D01*
Y-20939D01*
X374700D01*
Y-20993D01*
X374646D01*
Y-21047D01*
X374592D01*
Y-21101D01*
Y-21155D01*
Y-21209D01*
Y-21263D01*
Y-21317D01*
Y-21371D01*
Y-21425D01*
Y-21479D01*
Y-21533D01*
Y-21587D01*
Y-21642D01*
Y-21696D01*
Y-21750D01*
Y-21804D01*
Y-21858D01*
Y-21912D01*
Y-21966D01*
Y-22020D01*
Y-22074D01*
Y-22128D01*
Y-22182D01*
Y-22236D01*
Y-22290D01*
Y-22344D01*
Y-22398D01*
Y-22452D01*
Y-22506D01*
Y-22561D01*
Y-22615D01*
Y-22669D01*
Y-22723D01*
Y-22777D01*
Y-22831D01*
Y-22885D01*
Y-22939D01*
Y-22993D01*
Y-23047D01*
Y-23101D01*
Y-23155D01*
Y-23209D01*
Y-23263D01*
Y-23317D01*
Y-23371D01*
Y-23426D01*
Y-23480D01*
Y-23534D01*
Y-23588D01*
Y-23642D01*
Y-23696D01*
Y-23750D01*
Y-23804D01*
Y-23858D01*
Y-23912D01*
Y-23966D01*
Y-24020D01*
Y-24074D01*
Y-24128D01*
Y-24182D01*
Y-24237D01*
Y-24291D01*
Y-24345D01*
Y-24399D01*
Y-24453D01*
Y-24507D01*
Y-24561D01*
Y-24615D01*
Y-24669D01*
Y-24723D01*
Y-24777D01*
Y-24831D01*
Y-24885D01*
Y-24939D01*
Y-24993D01*
Y-25047D01*
Y-25102D01*
Y-25155D01*
Y-25210D01*
Y-25264D01*
Y-25318D01*
Y-25372D01*
Y-25426D01*
Y-25480D01*
Y-25534D01*
Y-25588D01*
Y-25642D01*
Y-25696D01*
Y-25750D01*
Y-25804D01*
Y-25858D01*
Y-25912D01*
Y-25967D01*
Y-26021D01*
Y-26075D01*
Y-26129D01*
Y-26183D01*
Y-26237D01*
Y-26291D01*
Y-26345D01*
Y-26399D01*
Y-26453D01*
Y-26507D01*
Y-26561D01*
Y-26615D01*
Y-26669D01*
Y-26723D01*
Y-26777D01*
Y-26831D01*
Y-26886D01*
Y-26940D01*
Y-26994D01*
Y-27048D01*
Y-27102D01*
Y-27156D01*
Y-27210D01*
Y-27264D01*
Y-27318D01*
Y-27372D01*
Y-27426D01*
Y-27480D01*
Y-27534D01*
Y-27588D01*
Y-27642D01*
Y-27696D01*
Y-27751D01*
Y-27805D01*
Y-27859D01*
Y-27913D01*
Y-27967D01*
Y-28021D01*
Y-28075D01*
Y-28129D01*
Y-28183D01*
Y-28237D01*
Y-28291D01*
Y-28345D01*
Y-28399D01*
Y-28453D01*
Y-28507D01*
Y-28561D01*
Y-28615D01*
Y-28670D01*
Y-28724D01*
Y-28778D01*
Y-28832D01*
Y-28886D01*
Y-28940D01*
Y-28994D01*
Y-29048D01*
Y-29102D01*
Y-29156D01*
Y-29210D01*
Y-29264D01*
Y-29318D01*
Y-29372D01*
Y-29426D01*
Y-29480D01*
Y-29535D01*
Y-29589D01*
Y-29643D01*
Y-29697D01*
Y-29751D01*
Y-29805D01*
Y-29859D01*
Y-29913D01*
Y-29967D01*
Y-30021D01*
Y-30075D01*
Y-30129D01*
Y-30183D01*
Y-30237D01*
Y-30291D01*
Y-30345D01*
Y-30400D01*
Y-30454D01*
Y-30508D01*
Y-30562D01*
Y-30616D01*
Y-30670D01*
Y-30724D01*
Y-30778D01*
Y-30832D01*
Y-30886D01*
Y-30940D01*
Y-30994D01*
Y-31048D01*
Y-31102D01*
Y-31156D01*
Y-31211D01*
Y-31265D01*
Y-31319D01*
Y-31373D01*
Y-31427D01*
Y-31481D01*
Y-31535D01*
Y-31589D01*
Y-31643D01*
Y-31697D01*
Y-31751D01*
Y-31805D01*
Y-31859D01*
Y-31913D01*
Y-31967D01*
Y-32021D01*
Y-32076D01*
Y-32129D01*
Y-32184D01*
Y-32238D01*
Y-32292D01*
Y-32346D01*
Y-32400D01*
Y-32454D01*
Y-32508D01*
Y-32562D01*
X374646D01*
Y-32616D01*
X374700D01*
Y-32670D01*
X377403D01*
Y-32616D01*
X377457D01*
Y-32562D01*
X377511D01*
Y-32508D01*
Y-32454D01*
X377565D01*
Y-32400D01*
Y-32346D01*
Y-32292D01*
Y-32238D01*
Y-32184D01*
Y-32129D01*
Y-32076D01*
Y-32021D01*
Y-31967D01*
Y-31913D01*
Y-31859D01*
Y-31805D01*
Y-31751D01*
Y-31697D01*
Y-31643D01*
Y-31589D01*
Y-31535D01*
Y-31481D01*
Y-31427D01*
Y-31373D01*
Y-31319D01*
Y-31265D01*
Y-31211D01*
Y-31156D01*
Y-31102D01*
Y-31048D01*
Y-30994D01*
Y-30940D01*
Y-30886D01*
Y-30832D01*
Y-30778D01*
Y-30724D01*
Y-30670D01*
Y-30616D01*
Y-30562D01*
Y-30508D01*
Y-30454D01*
Y-30400D01*
Y-30345D01*
Y-30291D01*
Y-30237D01*
Y-30183D01*
Y-30129D01*
Y-30075D01*
Y-30021D01*
Y-29967D01*
Y-29913D01*
Y-29859D01*
Y-29805D01*
Y-29751D01*
Y-29697D01*
Y-29643D01*
Y-29589D01*
Y-29535D01*
Y-29480D01*
Y-29426D01*
Y-29372D01*
Y-29318D01*
Y-29264D01*
Y-29210D01*
Y-29156D01*
Y-29102D01*
Y-29048D01*
Y-28994D01*
Y-28940D01*
Y-28886D01*
Y-28832D01*
Y-28778D01*
Y-28724D01*
Y-28670D01*
Y-28615D01*
Y-28561D01*
Y-28507D01*
Y-28453D01*
Y-28399D01*
Y-28345D01*
Y-28291D01*
Y-28237D01*
Y-28183D01*
Y-28129D01*
Y-28075D01*
Y-28021D01*
Y-27967D01*
Y-27913D01*
Y-27859D01*
Y-27805D01*
Y-27751D01*
Y-27696D01*
Y-27642D01*
Y-27588D01*
Y-27534D01*
Y-27480D01*
Y-27426D01*
Y-27372D01*
Y-27318D01*
Y-27264D01*
Y-27210D01*
Y-27156D01*
Y-27102D01*
Y-27048D01*
Y-26994D01*
Y-26940D01*
Y-26886D01*
Y-26831D01*
Y-26777D01*
Y-26723D01*
Y-26669D01*
Y-26615D01*
Y-26561D01*
Y-26507D01*
Y-26453D01*
Y-26399D01*
Y-26345D01*
Y-26291D01*
Y-26237D01*
Y-26183D01*
Y-26129D01*
Y-26075D01*
Y-26021D01*
Y-25967D01*
Y-25912D01*
Y-25858D01*
Y-25804D01*
Y-25750D01*
Y-25696D01*
Y-25642D01*
Y-25588D01*
Y-25534D01*
Y-25480D01*
Y-25426D01*
Y-25372D01*
Y-25318D01*
Y-25264D01*
Y-25210D01*
Y-25155D01*
Y-25102D01*
Y-25047D01*
Y-24993D01*
Y-24939D01*
Y-24885D01*
Y-24831D01*
Y-24777D01*
Y-24723D01*
Y-24669D01*
Y-24615D01*
Y-24561D01*
Y-24507D01*
Y-24453D01*
Y-24399D01*
Y-24345D01*
Y-24291D01*
Y-24237D01*
Y-24182D01*
Y-24128D01*
Y-24074D01*
Y-24020D01*
Y-23966D01*
Y-23912D01*
Y-23858D01*
Y-23804D01*
Y-23750D01*
Y-23696D01*
Y-23642D01*
Y-23588D01*
Y-23534D01*
Y-23480D01*
Y-23426D01*
Y-23371D01*
Y-23317D01*
Y-23263D01*
Y-23209D01*
Y-23155D01*
Y-23101D01*
Y-23047D01*
Y-22993D01*
Y-22939D01*
Y-22885D01*
Y-22831D01*
Y-22777D01*
Y-22723D01*
Y-22669D01*
Y-22615D01*
Y-22561D01*
Y-22506D01*
Y-22452D01*
Y-22398D01*
Y-22344D01*
Y-22290D01*
Y-22236D01*
Y-22182D01*
Y-22128D01*
Y-22074D01*
Y-22020D01*
Y-21966D01*
Y-21912D01*
Y-21858D01*
Y-21804D01*
Y-21750D01*
Y-21696D01*
Y-21642D01*
Y-21587D01*
Y-21533D01*
Y-21479D01*
Y-21425D01*
Y-21371D01*
Y-21317D01*
Y-21263D01*
Y-21209D01*
Y-21155D01*
X377511D01*
Y-21101D01*
Y-21047D01*
X377457D01*
Y-20993D01*
Y-20939D01*
X377295D01*
Y-20885D01*
D02*
G37*
G36*
X372970D02*
X364699D01*
Y-20939D01*
Y-20993D01*
Y-21047D01*
Y-21101D01*
Y-21155D01*
Y-21209D01*
Y-21263D01*
Y-21317D01*
Y-21371D01*
Y-21425D01*
Y-21479D01*
Y-21533D01*
Y-21587D01*
Y-21642D01*
Y-21696D01*
Y-21750D01*
Y-21804D01*
Y-21858D01*
Y-21912D01*
Y-21966D01*
Y-22020D01*
Y-22074D01*
Y-22128D01*
Y-22182D01*
Y-22236D01*
Y-22290D01*
Y-22344D01*
Y-22398D01*
Y-22452D01*
Y-22506D01*
Y-22561D01*
Y-22615D01*
Y-22669D01*
Y-22723D01*
Y-22777D01*
Y-22831D01*
Y-22885D01*
Y-22939D01*
Y-22993D01*
Y-23047D01*
Y-23101D01*
Y-23155D01*
Y-23209D01*
Y-23263D01*
Y-23317D01*
Y-23371D01*
Y-23426D01*
Y-23480D01*
Y-23534D01*
Y-23588D01*
Y-23642D01*
Y-23696D01*
Y-23750D01*
Y-23804D01*
X364861D01*
Y-23750D01*
X364915D01*
Y-23804D01*
X365672D01*
Y-23858D01*
Y-23912D01*
Y-23966D01*
Y-24020D01*
Y-24074D01*
Y-24128D01*
Y-24182D01*
Y-24237D01*
Y-24291D01*
Y-24345D01*
Y-24399D01*
Y-24453D01*
Y-24507D01*
Y-24561D01*
Y-24615D01*
Y-24669D01*
Y-24723D01*
Y-24777D01*
Y-24831D01*
Y-24885D01*
Y-24939D01*
Y-24993D01*
Y-25047D01*
Y-25102D01*
Y-25155D01*
Y-25210D01*
Y-25264D01*
Y-25318D01*
Y-25372D01*
Y-25426D01*
Y-25480D01*
Y-25534D01*
Y-25588D01*
Y-25642D01*
Y-25696D01*
Y-25750D01*
Y-25804D01*
Y-25858D01*
Y-25912D01*
Y-25967D01*
Y-26021D01*
Y-26075D01*
Y-26129D01*
Y-26183D01*
Y-26237D01*
Y-26291D01*
Y-26345D01*
Y-26399D01*
Y-26453D01*
Y-26507D01*
Y-26561D01*
Y-26615D01*
Y-26669D01*
Y-26723D01*
Y-26777D01*
Y-26831D01*
Y-26886D01*
Y-26940D01*
Y-26994D01*
Y-27048D01*
Y-27102D01*
Y-27156D01*
Y-27210D01*
Y-27264D01*
Y-27318D01*
Y-27372D01*
Y-27426D01*
Y-27480D01*
Y-27534D01*
Y-27588D01*
Y-27642D01*
Y-27696D01*
Y-27751D01*
Y-27805D01*
Y-27859D01*
Y-27913D01*
Y-27967D01*
Y-28021D01*
Y-28075D01*
Y-28129D01*
Y-28183D01*
Y-28237D01*
Y-28291D01*
Y-28345D01*
Y-28399D01*
Y-28453D01*
Y-28507D01*
Y-28561D01*
Y-28615D01*
Y-28670D01*
Y-28724D01*
Y-28778D01*
Y-28832D01*
Y-28886D01*
Y-28940D01*
Y-28994D01*
Y-29048D01*
Y-29102D01*
Y-29156D01*
Y-29210D01*
Y-29264D01*
Y-29318D01*
Y-29372D01*
Y-29426D01*
Y-29480D01*
Y-29535D01*
Y-29589D01*
Y-29643D01*
Y-29697D01*
Y-29751D01*
Y-29805D01*
Y-29859D01*
Y-29913D01*
Y-29967D01*
Y-30021D01*
Y-30075D01*
Y-30129D01*
Y-30183D01*
Y-30237D01*
Y-30291D01*
Y-30345D01*
Y-30400D01*
Y-30454D01*
Y-30508D01*
Y-30562D01*
Y-30616D01*
Y-30670D01*
Y-30724D01*
Y-30778D01*
Y-30832D01*
Y-30886D01*
Y-30940D01*
Y-30994D01*
Y-31048D01*
Y-31102D01*
Y-31156D01*
Y-31211D01*
Y-31265D01*
Y-31319D01*
Y-31373D01*
Y-31427D01*
Y-31481D01*
Y-31535D01*
Y-31589D01*
Y-31643D01*
Y-31697D01*
Y-31751D01*
Y-31805D01*
Y-31859D01*
Y-31913D01*
Y-31967D01*
Y-32021D01*
Y-32076D01*
Y-32129D01*
Y-32184D01*
Y-32238D01*
Y-32292D01*
Y-32346D01*
Y-32400D01*
Y-32454D01*
Y-32508D01*
X365726D01*
Y-32562D01*
X365780D01*
Y-32616D01*
X365834D01*
Y-32670D01*
X368213D01*
Y-32616D01*
X368321D01*
Y-32562D01*
X368375D01*
Y-32508D01*
Y-32454D01*
X368429D01*
Y-32400D01*
Y-32346D01*
Y-32292D01*
Y-32238D01*
Y-32184D01*
Y-32129D01*
Y-32076D01*
Y-32021D01*
Y-31967D01*
Y-31913D01*
Y-31859D01*
Y-31805D01*
Y-31751D01*
Y-31697D01*
Y-31643D01*
Y-31589D01*
Y-31535D01*
Y-31481D01*
Y-31427D01*
Y-31373D01*
Y-31319D01*
Y-31265D01*
Y-31211D01*
Y-31156D01*
Y-31102D01*
Y-31048D01*
Y-30994D01*
Y-30940D01*
Y-30886D01*
Y-30832D01*
Y-30778D01*
Y-30724D01*
Y-30670D01*
Y-30616D01*
Y-30562D01*
Y-30508D01*
Y-30454D01*
Y-30400D01*
Y-30345D01*
Y-30291D01*
Y-30237D01*
Y-30183D01*
Y-30129D01*
Y-30075D01*
Y-30021D01*
Y-29967D01*
Y-29913D01*
Y-29859D01*
Y-29805D01*
Y-29751D01*
Y-29697D01*
Y-29643D01*
Y-29589D01*
Y-29535D01*
Y-29480D01*
Y-29426D01*
Y-29372D01*
Y-29318D01*
Y-29264D01*
Y-29210D01*
Y-29156D01*
Y-29102D01*
Y-29048D01*
Y-28994D01*
Y-28940D01*
Y-28886D01*
Y-28832D01*
Y-28778D01*
Y-28724D01*
Y-28670D01*
Y-28615D01*
Y-28561D01*
Y-28507D01*
Y-28453D01*
Y-28399D01*
Y-28345D01*
Y-28291D01*
Y-28237D01*
Y-28183D01*
Y-28129D01*
Y-28075D01*
Y-28021D01*
Y-27967D01*
Y-27913D01*
Y-27859D01*
Y-27805D01*
Y-27751D01*
Y-27696D01*
Y-27642D01*
Y-27588D01*
Y-27534D01*
Y-27480D01*
Y-27426D01*
Y-27372D01*
Y-27318D01*
Y-27264D01*
Y-27210D01*
Y-27156D01*
Y-27102D01*
Y-27048D01*
Y-26994D01*
Y-26940D01*
Y-26886D01*
Y-26831D01*
Y-26777D01*
Y-26723D01*
Y-26669D01*
Y-26615D01*
Y-26561D01*
Y-26507D01*
Y-26453D01*
Y-26399D01*
Y-26345D01*
Y-26291D01*
Y-26237D01*
Y-26183D01*
Y-26129D01*
Y-26075D01*
Y-26021D01*
Y-25967D01*
Y-25912D01*
Y-25858D01*
Y-25804D01*
Y-25750D01*
Y-25696D01*
Y-25642D01*
Y-25588D01*
Y-25534D01*
Y-25480D01*
Y-25426D01*
Y-25372D01*
Y-25318D01*
Y-25264D01*
Y-25210D01*
Y-25155D01*
Y-25102D01*
Y-25047D01*
Y-24993D01*
Y-24939D01*
Y-24885D01*
Y-24831D01*
Y-24777D01*
Y-24723D01*
Y-24669D01*
Y-24615D01*
Y-24561D01*
Y-24507D01*
Y-24453D01*
Y-24399D01*
Y-24345D01*
Y-24291D01*
Y-24237D01*
Y-24182D01*
Y-24128D01*
Y-24074D01*
Y-24020D01*
Y-23966D01*
Y-23912D01*
Y-23858D01*
Y-23804D01*
X370267D01*
Y-23858D01*
Y-23912D01*
Y-23966D01*
Y-24020D01*
Y-24074D01*
Y-24128D01*
Y-24182D01*
Y-24237D01*
Y-24291D01*
Y-24345D01*
Y-24399D01*
Y-24453D01*
Y-24507D01*
Y-24561D01*
Y-24615D01*
Y-24669D01*
Y-24723D01*
Y-24777D01*
Y-24831D01*
Y-24885D01*
Y-24939D01*
Y-24993D01*
Y-25047D01*
Y-25102D01*
Y-25155D01*
Y-25210D01*
Y-25264D01*
Y-25318D01*
Y-25372D01*
Y-25426D01*
Y-25480D01*
Y-25534D01*
Y-25588D01*
Y-25642D01*
Y-25696D01*
Y-25750D01*
Y-25804D01*
Y-25858D01*
Y-25912D01*
Y-25967D01*
Y-26021D01*
Y-26075D01*
Y-26129D01*
Y-26183D01*
Y-26237D01*
Y-26291D01*
Y-26345D01*
Y-26399D01*
Y-26453D01*
Y-26507D01*
Y-26561D01*
Y-26615D01*
Y-26669D01*
Y-26723D01*
Y-26777D01*
Y-26831D01*
Y-26886D01*
Y-26940D01*
Y-26994D01*
Y-27048D01*
Y-27102D01*
Y-27156D01*
Y-27210D01*
Y-27264D01*
Y-27318D01*
Y-27372D01*
Y-27426D01*
Y-27480D01*
Y-27534D01*
Y-27588D01*
Y-27642D01*
Y-27696D01*
Y-27751D01*
Y-27805D01*
Y-27859D01*
Y-27913D01*
Y-27967D01*
Y-28021D01*
Y-28075D01*
Y-28129D01*
Y-28183D01*
Y-28237D01*
Y-28291D01*
Y-28345D01*
Y-28399D01*
Y-28453D01*
Y-28507D01*
Y-28561D01*
Y-28615D01*
Y-28670D01*
Y-28724D01*
Y-28778D01*
Y-28832D01*
Y-28886D01*
Y-28940D01*
Y-28994D01*
Y-29048D01*
Y-29102D01*
Y-29156D01*
Y-29210D01*
Y-29264D01*
Y-29318D01*
Y-29372D01*
Y-29426D01*
Y-29480D01*
Y-29535D01*
Y-29589D01*
Y-29643D01*
Y-29697D01*
Y-29751D01*
Y-29805D01*
Y-29859D01*
Y-29913D01*
Y-29967D01*
Y-30021D01*
Y-30075D01*
Y-30129D01*
Y-30183D01*
Y-30237D01*
Y-30291D01*
Y-30345D01*
Y-30400D01*
Y-30454D01*
Y-30508D01*
Y-30562D01*
Y-30616D01*
Y-30670D01*
Y-30724D01*
Y-30778D01*
Y-30832D01*
Y-30886D01*
Y-30940D01*
Y-30994D01*
Y-31048D01*
Y-31102D01*
Y-31156D01*
Y-31211D01*
Y-31265D01*
Y-31319D01*
Y-31373D01*
Y-31427D01*
Y-31481D01*
Y-31535D01*
Y-31589D01*
Y-31643D01*
Y-31697D01*
Y-31751D01*
Y-31805D01*
Y-31859D01*
Y-31913D01*
Y-31967D01*
Y-32021D01*
Y-32076D01*
Y-32129D01*
Y-32184D01*
Y-32238D01*
Y-32292D01*
Y-32346D01*
Y-32400D01*
Y-32454D01*
X370321D01*
Y-32508D01*
Y-32562D01*
X370375D01*
Y-32616D01*
X370429D01*
Y-32670D01*
X373078D01*
Y-32616D01*
X373186D01*
Y-32562D01*
Y-32508D01*
X373240D01*
Y-32454D01*
Y-32400D01*
Y-32346D01*
Y-32292D01*
Y-32238D01*
Y-32184D01*
Y-32129D01*
Y-32076D01*
Y-32021D01*
Y-31967D01*
Y-31913D01*
Y-31859D01*
Y-31805D01*
Y-31751D01*
Y-31697D01*
Y-31643D01*
Y-31589D01*
Y-31535D01*
Y-31481D01*
Y-31427D01*
Y-31373D01*
Y-31319D01*
Y-31265D01*
Y-31211D01*
Y-31156D01*
Y-31102D01*
Y-31048D01*
Y-30994D01*
Y-30940D01*
Y-30886D01*
Y-30832D01*
Y-30778D01*
Y-30724D01*
Y-30670D01*
Y-30616D01*
Y-30562D01*
Y-30508D01*
Y-30454D01*
Y-30400D01*
Y-30345D01*
Y-30291D01*
Y-30237D01*
Y-30183D01*
Y-30129D01*
Y-30075D01*
Y-30021D01*
Y-29967D01*
Y-29913D01*
Y-29859D01*
Y-29805D01*
Y-29751D01*
Y-29697D01*
Y-29643D01*
Y-29589D01*
Y-29535D01*
Y-29480D01*
Y-29426D01*
Y-29372D01*
Y-29318D01*
Y-29264D01*
Y-29210D01*
Y-29156D01*
Y-29102D01*
Y-29048D01*
Y-28994D01*
Y-28940D01*
Y-28886D01*
Y-28832D01*
Y-28778D01*
Y-28724D01*
Y-28670D01*
Y-28615D01*
Y-28561D01*
Y-28507D01*
Y-28453D01*
Y-28399D01*
Y-28345D01*
Y-28291D01*
Y-28237D01*
Y-28183D01*
Y-28129D01*
Y-28075D01*
Y-28021D01*
Y-27967D01*
Y-27913D01*
Y-27859D01*
Y-27805D01*
Y-27751D01*
Y-27696D01*
Y-27642D01*
Y-27588D01*
Y-27534D01*
Y-27480D01*
Y-27426D01*
Y-27372D01*
Y-27318D01*
Y-27264D01*
Y-27210D01*
Y-27156D01*
Y-27102D01*
Y-27048D01*
Y-26994D01*
Y-26940D01*
Y-26886D01*
Y-26831D01*
Y-26777D01*
Y-26723D01*
Y-26669D01*
Y-26615D01*
Y-26561D01*
Y-26507D01*
Y-26453D01*
Y-26399D01*
Y-26345D01*
Y-26291D01*
Y-26237D01*
Y-26183D01*
Y-26129D01*
Y-26075D01*
Y-26021D01*
Y-25967D01*
Y-25912D01*
Y-25858D01*
Y-25804D01*
Y-25750D01*
Y-25696D01*
Y-25642D01*
Y-25588D01*
Y-25534D01*
Y-25480D01*
Y-25426D01*
Y-25372D01*
Y-25318D01*
Y-25264D01*
Y-25210D01*
Y-25155D01*
Y-25102D01*
Y-25047D01*
Y-24993D01*
Y-24939D01*
Y-24885D01*
Y-24831D01*
Y-24777D01*
Y-24723D01*
Y-24669D01*
Y-24615D01*
Y-24561D01*
Y-24507D01*
Y-24453D01*
Y-24399D01*
Y-24345D01*
Y-24291D01*
Y-24237D01*
Y-24182D01*
Y-24128D01*
Y-24074D01*
Y-24020D01*
Y-23966D01*
Y-23912D01*
Y-23858D01*
Y-23804D01*
Y-23750D01*
Y-23696D01*
Y-23642D01*
Y-23588D01*
Y-23534D01*
Y-23480D01*
Y-23426D01*
Y-23371D01*
Y-23317D01*
Y-23263D01*
Y-23209D01*
Y-23155D01*
Y-23101D01*
Y-23047D01*
Y-22993D01*
Y-22939D01*
Y-22885D01*
Y-22831D01*
Y-22777D01*
Y-22723D01*
Y-22669D01*
Y-22615D01*
Y-22561D01*
Y-22506D01*
Y-22452D01*
Y-22398D01*
Y-22344D01*
Y-22290D01*
Y-22236D01*
Y-22182D01*
Y-22128D01*
Y-22074D01*
Y-22020D01*
Y-21966D01*
Y-21912D01*
Y-21858D01*
Y-21804D01*
Y-21750D01*
Y-21696D01*
Y-21642D01*
Y-21587D01*
Y-21533D01*
Y-21479D01*
Y-21425D01*
Y-21371D01*
Y-21317D01*
Y-21263D01*
Y-21209D01*
Y-21155D01*
Y-21101D01*
X373186D01*
Y-21047D01*
Y-20993D01*
X373132D01*
Y-20939D01*
X372970D01*
Y-20885D01*
D02*
G37*
G36*
X375187Y-33643D02*
X368699D01*
Y-33697D01*
X368645D01*
Y-33643D01*
X368537D01*
Y-33697D01*
X368375D01*
Y-33751D01*
X368321D01*
Y-33806D01*
X368267D01*
Y-33860D01*
Y-33914D01*
Y-33968D01*
Y-34022D01*
Y-34076D01*
Y-34130D01*
Y-34184D01*
Y-34238D01*
Y-34292D01*
Y-34346D01*
Y-34400D01*
Y-34454D01*
Y-34508D01*
Y-34562D01*
Y-34616D01*
Y-34670D01*
Y-34725D01*
Y-34779D01*
Y-34833D01*
Y-34887D01*
Y-34941D01*
Y-34995D01*
Y-35049D01*
Y-35103D01*
Y-35157D01*
Y-35211D01*
Y-35265D01*
Y-35319D01*
Y-35373D01*
Y-35427D01*
Y-35481D01*
Y-35535D01*
Y-35590D01*
Y-35644D01*
Y-35698D01*
Y-35752D01*
Y-35806D01*
Y-35860D01*
Y-35914D01*
Y-35968D01*
Y-36022D01*
Y-36076D01*
Y-36130D01*
Y-36184D01*
Y-36238D01*
Y-36292D01*
Y-36346D01*
Y-36400D01*
X368321D01*
Y-36454D01*
X368375D01*
Y-36509D01*
X368537D01*
Y-36563D01*
X368753D01*
Y-36509D01*
X368807D01*
Y-36563D01*
X374159D01*
Y-36617D01*
X374214D01*
Y-36671D01*
X374268D01*
Y-36725D01*
Y-36779D01*
Y-36833D01*
Y-36887D01*
Y-36941D01*
Y-36995D01*
Y-37049D01*
Y-37103D01*
Y-37157D01*
Y-37211D01*
Y-37265D01*
Y-37319D01*
Y-37374D01*
Y-37428D01*
Y-37482D01*
Y-37536D01*
Y-37590D01*
Y-37644D01*
Y-37698D01*
Y-37752D01*
Y-37806D01*
Y-37860D01*
Y-37914D01*
Y-37968D01*
Y-38022D01*
Y-38076D01*
Y-38130D01*
Y-38184D01*
Y-38238D01*
Y-38293D01*
Y-38347D01*
Y-38401D01*
Y-38455D01*
Y-38509D01*
Y-38563D01*
Y-38617D01*
Y-38671D01*
Y-38725D01*
Y-38779D01*
Y-38833D01*
Y-38887D01*
Y-38941D01*
Y-38995D01*
Y-39050D01*
Y-39103D01*
Y-39158D01*
Y-39212D01*
Y-39266D01*
Y-39320D01*
Y-39374D01*
Y-39428D01*
Y-39482D01*
Y-39536D01*
Y-39590D01*
Y-39644D01*
Y-39698D01*
Y-39752D01*
Y-39806D01*
Y-39860D01*
Y-39915D01*
Y-39968D01*
Y-40023D01*
Y-40077D01*
Y-40131D01*
Y-40185D01*
Y-40239D01*
Y-40293D01*
Y-40347D01*
Y-40401D01*
Y-40455D01*
Y-40509D01*
Y-40563D01*
Y-40617D01*
Y-40671D01*
Y-40725D01*
Y-40780D01*
Y-40834D01*
Y-40888D01*
Y-40942D01*
Y-40996D01*
Y-41050D01*
Y-41104D01*
Y-41158D01*
Y-41212D01*
Y-41266D01*
Y-41320D01*
Y-41374D01*
Y-41428D01*
Y-41482D01*
Y-41536D01*
Y-41590D01*
Y-41644D01*
Y-41699D01*
Y-41753D01*
Y-41807D01*
Y-41861D01*
Y-41915D01*
Y-41969D01*
Y-42023D01*
Y-42077D01*
Y-42131D01*
Y-42185D01*
Y-42239D01*
Y-42293D01*
Y-42347D01*
Y-42401D01*
X374214D01*
Y-42455D01*
Y-42509D01*
X374105D01*
Y-42564D01*
X368483D01*
Y-42618D01*
X368375D01*
Y-42672D01*
X368321D01*
Y-42726D01*
X368267D01*
Y-42780D01*
Y-42834D01*
Y-42888D01*
Y-42942D01*
Y-42996D01*
Y-43050D01*
Y-43104D01*
Y-43158D01*
Y-43212D01*
Y-43266D01*
Y-43320D01*
Y-43374D01*
Y-43429D01*
Y-43483D01*
Y-43537D01*
Y-43591D01*
Y-43645D01*
Y-43699D01*
Y-43753D01*
Y-43807D01*
Y-43861D01*
Y-43915D01*
Y-43969D01*
Y-44023D01*
Y-44077D01*
Y-44131D01*
Y-44185D01*
Y-44239D01*
Y-44293D01*
Y-44348D01*
Y-44402D01*
Y-44456D01*
Y-44510D01*
Y-44564D01*
Y-44618D01*
Y-44672D01*
Y-44726D01*
Y-44780D01*
Y-44834D01*
Y-44888D01*
Y-44942D01*
Y-44996D01*
Y-45050D01*
Y-45104D01*
Y-45158D01*
Y-45213D01*
Y-45267D01*
X368321D01*
Y-45321D01*
X368375D01*
Y-45375D01*
X368429D01*
Y-45429D01*
X375295D01*
Y-45375D01*
X375457D01*
Y-45321D01*
X375565D01*
Y-45267D01*
X375619D01*
Y-45213D01*
X375673D01*
Y-45158D01*
X375727D01*
Y-45104D01*
X375781D01*
Y-45050D01*
X375835D01*
Y-44996D01*
X375889D01*
Y-44942D01*
X375943D01*
Y-44888D01*
X375997D01*
Y-44834D01*
X376052D01*
Y-44780D01*
X376106D01*
Y-44726D01*
X376160D01*
Y-44672D01*
X376214D01*
Y-44618D01*
X376268D01*
Y-44564D01*
X376322D01*
Y-44510D01*
X376376D01*
Y-44456D01*
X376430D01*
Y-44402D01*
X376484D01*
Y-44348D01*
X376538D01*
Y-44293D01*
X376592D01*
Y-44239D01*
X376646D01*
Y-44185D01*
X376700D01*
Y-44131D01*
X376754D01*
Y-44077D01*
X376809D01*
Y-44023D01*
X376863D01*
Y-43969D01*
X376917D01*
Y-43915D01*
X376971D01*
Y-43861D01*
X377025D01*
Y-43807D01*
X377079D01*
Y-43753D01*
X377133D01*
Y-43699D01*
Y-43645D01*
X377187D01*
Y-43591D01*
Y-43537D01*
Y-43483D01*
X377241D01*
Y-43429D01*
Y-43374D01*
Y-43320D01*
Y-43266D01*
Y-43212D01*
Y-43158D01*
Y-43104D01*
Y-43050D01*
Y-42996D01*
Y-42942D01*
Y-42888D01*
Y-42834D01*
Y-42780D01*
Y-42726D01*
Y-42672D01*
Y-42618D01*
Y-42564D01*
Y-42509D01*
Y-42455D01*
Y-42401D01*
Y-42347D01*
Y-42293D01*
Y-42239D01*
Y-42185D01*
Y-42131D01*
Y-42077D01*
Y-42023D01*
Y-41969D01*
Y-41915D01*
Y-41861D01*
Y-41807D01*
Y-41753D01*
Y-41699D01*
Y-41644D01*
Y-41590D01*
Y-41536D01*
Y-41482D01*
Y-41428D01*
Y-41374D01*
Y-41320D01*
Y-41266D01*
Y-41212D01*
Y-41158D01*
Y-41104D01*
Y-41050D01*
Y-40996D01*
Y-40942D01*
Y-40888D01*
Y-40834D01*
Y-40780D01*
Y-40725D01*
Y-40671D01*
Y-40617D01*
Y-40563D01*
Y-40509D01*
Y-40455D01*
Y-40401D01*
Y-40347D01*
Y-40293D01*
Y-40239D01*
Y-40185D01*
Y-40131D01*
Y-40077D01*
Y-40023D01*
Y-39968D01*
Y-39915D01*
Y-39860D01*
Y-39806D01*
Y-39752D01*
Y-39698D01*
Y-39644D01*
Y-39590D01*
Y-39536D01*
Y-39482D01*
Y-39428D01*
Y-39374D01*
Y-39320D01*
Y-39266D01*
Y-39212D01*
Y-39158D01*
Y-39103D01*
Y-39050D01*
Y-38995D01*
Y-38941D01*
Y-38887D01*
Y-38833D01*
Y-38779D01*
Y-38725D01*
Y-38671D01*
Y-38617D01*
Y-38563D01*
Y-38509D01*
Y-38455D01*
Y-38401D01*
Y-38347D01*
Y-38293D01*
Y-38238D01*
Y-38184D01*
Y-38130D01*
Y-38076D01*
Y-38022D01*
Y-37968D01*
Y-37914D01*
Y-37860D01*
Y-37806D01*
Y-37752D01*
Y-37698D01*
Y-37644D01*
Y-37590D01*
Y-37536D01*
Y-37482D01*
Y-37428D01*
Y-37374D01*
Y-37319D01*
Y-37265D01*
Y-37211D01*
Y-37157D01*
Y-37103D01*
Y-37049D01*
Y-36995D01*
Y-36941D01*
Y-36887D01*
Y-36833D01*
Y-36779D01*
Y-36725D01*
Y-36671D01*
Y-36617D01*
Y-36563D01*
Y-36509D01*
Y-36454D01*
Y-36400D01*
Y-36346D01*
Y-36292D01*
Y-36238D01*
Y-36184D01*
Y-36130D01*
Y-36076D01*
Y-36022D01*
Y-35968D01*
Y-35914D01*
Y-35860D01*
Y-35806D01*
Y-35752D01*
Y-35698D01*
Y-35644D01*
X377187D01*
Y-35590D01*
Y-35535D01*
Y-35481D01*
Y-35427D01*
X377133D01*
Y-35373D01*
Y-35319D01*
X377079D01*
Y-35265D01*
X377025D01*
Y-35211D01*
X376971D01*
Y-35157D01*
X376917D01*
Y-35103D01*
X376863D01*
Y-35049D01*
X376809D01*
Y-34995D01*
X376754D01*
Y-34941D01*
X376700D01*
Y-34887D01*
X376646D01*
Y-34833D01*
X376592D01*
Y-34779D01*
X376538D01*
Y-34725D01*
X376484D01*
Y-34670D01*
X376430D01*
Y-34616D01*
X376376D01*
Y-34562D01*
X376322D01*
Y-34508D01*
X376268D01*
Y-34454D01*
X376214D01*
Y-34400D01*
X376160D01*
Y-34346D01*
X376106D01*
Y-34292D01*
X376052D01*
Y-34238D01*
X375997D01*
Y-34184D01*
X375943D01*
Y-34130D01*
X375889D01*
Y-34076D01*
X375835D01*
Y-34022D01*
X375781D01*
Y-33968D01*
X375727D01*
Y-33914D01*
X375673D01*
Y-33860D01*
X375619D01*
Y-33806D01*
X375511D01*
Y-33751D01*
X375349D01*
Y-33697D01*
X375187D01*
Y-33643D01*
D02*
G37*
G36*
X363779Y-14451D02*
X362806D01*
Y-14505D01*
X362590D01*
Y-14559D01*
X362482D01*
Y-14614D01*
X362428D01*
Y-14668D01*
X362374D01*
Y-14722D01*
X362320D01*
Y-14776D01*
X362266D01*
Y-14830D01*
X362212D01*
Y-14884D01*
X362158D01*
Y-14938D01*
X362104D01*
Y-14992D01*
X362050D01*
Y-15046D01*
X361996D01*
Y-15100D01*
X361941D01*
Y-15154D01*
X361887D01*
Y-15208D01*
X361833D01*
Y-15262D01*
X361779D01*
Y-15316D01*
X361725D01*
Y-15370D01*
X361671D01*
Y-15424D01*
X361617D01*
Y-15478D01*
X361563D01*
Y-15532D01*
X361509D01*
Y-15587D01*
X361455D01*
Y-15641D01*
X361401D01*
Y-15695D01*
X361347D01*
Y-15749D01*
X361293D01*
Y-15803D01*
X361239D01*
Y-15857D01*
X361185D01*
Y-15911D01*
X361130D01*
Y-15965D01*
X361076D01*
Y-16019D01*
X361022D01*
Y-16073D01*
X360968D01*
Y-16127D01*
Y-16181D01*
X360914D01*
Y-16235D01*
Y-16289D01*
Y-16343D01*
Y-16398D01*
X360860D01*
Y-16452D01*
Y-16506D01*
Y-16560D01*
Y-16614D01*
Y-16668D01*
Y-16722D01*
Y-16776D01*
Y-16830D01*
Y-16884D01*
Y-16938D01*
Y-16992D01*
Y-17046D01*
Y-17100D01*
Y-17154D01*
Y-17208D01*
Y-17263D01*
Y-17317D01*
Y-17371D01*
Y-17425D01*
Y-17479D01*
Y-17533D01*
Y-17587D01*
Y-17641D01*
Y-17695D01*
Y-17749D01*
Y-17803D01*
Y-17857D01*
Y-17911D01*
Y-17965D01*
Y-18019D01*
Y-18073D01*
Y-18127D01*
Y-18181D01*
Y-18236D01*
Y-18290D01*
Y-18344D01*
Y-18398D01*
Y-18452D01*
Y-18506D01*
Y-18560D01*
Y-18614D01*
Y-18668D01*
Y-18722D01*
Y-18776D01*
Y-18830D01*
Y-18884D01*
Y-18938D01*
Y-18993D01*
Y-19047D01*
Y-19101D01*
Y-19155D01*
Y-19209D01*
Y-19263D01*
Y-19317D01*
Y-19371D01*
Y-19425D01*
Y-19479D01*
Y-19533D01*
Y-19587D01*
Y-19641D01*
Y-19695D01*
Y-19749D01*
Y-19803D01*
Y-19858D01*
Y-19911D01*
Y-19966D01*
Y-20020D01*
Y-20074D01*
Y-20128D01*
Y-20182D01*
Y-20236D01*
Y-20290D01*
Y-20344D01*
Y-20398D01*
Y-20452D01*
Y-20506D01*
Y-20560D01*
Y-20614D01*
Y-20668D01*
Y-20722D01*
Y-20776D01*
Y-20831D01*
Y-20885D01*
Y-20939D01*
Y-20993D01*
Y-21047D01*
Y-21101D01*
Y-21155D01*
Y-21209D01*
Y-21263D01*
Y-21317D01*
Y-21371D01*
Y-21425D01*
Y-21479D01*
Y-21533D01*
Y-21587D01*
Y-21642D01*
Y-21696D01*
Y-21750D01*
Y-21804D01*
Y-21858D01*
Y-21912D01*
Y-21966D01*
Y-22020D01*
Y-22074D01*
Y-22128D01*
Y-22182D01*
Y-22236D01*
Y-22290D01*
Y-22344D01*
Y-22398D01*
Y-22452D01*
Y-22506D01*
Y-22561D01*
Y-22615D01*
Y-22669D01*
Y-22723D01*
Y-22777D01*
Y-22831D01*
Y-22885D01*
Y-22939D01*
Y-22993D01*
Y-23047D01*
Y-23101D01*
Y-23155D01*
Y-23209D01*
Y-23263D01*
Y-23317D01*
Y-23371D01*
Y-23426D01*
Y-23480D01*
Y-23534D01*
Y-23588D01*
Y-23642D01*
Y-23696D01*
Y-23750D01*
Y-23804D01*
Y-23858D01*
Y-23912D01*
Y-23966D01*
Y-24020D01*
Y-24074D01*
Y-24128D01*
Y-24182D01*
Y-24237D01*
Y-24291D01*
Y-24345D01*
Y-24399D01*
Y-24453D01*
Y-24507D01*
Y-24561D01*
Y-24615D01*
Y-24669D01*
Y-24723D01*
Y-24777D01*
Y-24831D01*
Y-24885D01*
Y-24939D01*
Y-24993D01*
Y-25047D01*
Y-25102D01*
Y-25155D01*
Y-25210D01*
Y-25264D01*
Y-25318D01*
Y-25372D01*
Y-25426D01*
Y-25480D01*
Y-25534D01*
Y-25588D01*
Y-25642D01*
Y-25696D01*
Y-25750D01*
Y-25804D01*
Y-25858D01*
Y-25912D01*
Y-25967D01*
Y-26021D01*
Y-26075D01*
Y-26129D01*
Y-26183D01*
Y-26237D01*
Y-26291D01*
Y-26345D01*
Y-26399D01*
Y-26453D01*
Y-26507D01*
Y-26561D01*
Y-26615D01*
Y-26669D01*
Y-26723D01*
Y-26777D01*
Y-26831D01*
Y-26886D01*
Y-26940D01*
Y-26994D01*
Y-27048D01*
Y-27102D01*
Y-27156D01*
Y-27210D01*
Y-27264D01*
Y-27318D01*
Y-27372D01*
Y-27426D01*
Y-27480D01*
Y-27534D01*
Y-27588D01*
Y-27642D01*
Y-27696D01*
Y-27751D01*
Y-27805D01*
Y-27859D01*
Y-27913D01*
Y-27967D01*
Y-28021D01*
Y-28075D01*
Y-28129D01*
Y-28183D01*
Y-28237D01*
Y-28291D01*
Y-28345D01*
Y-28399D01*
Y-28453D01*
Y-28507D01*
Y-28561D01*
Y-28615D01*
Y-28670D01*
Y-28724D01*
Y-28778D01*
Y-28832D01*
Y-28886D01*
Y-28940D01*
Y-28994D01*
Y-29048D01*
Y-29102D01*
Y-29156D01*
Y-29210D01*
Y-29264D01*
Y-29318D01*
Y-29372D01*
Y-29426D01*
Y-29480D01*
Y-29535D01*
Y-29589D01*
Y-29643D01*
Y-29697D01*
Y-29751D01*
Y-29805D01*
Y-29859D01*
Y-29913D01*
Y-29967D01*
Y-30021D01*
Y-30075D01*
Y-30129D01*
Y-30183D01*
Y-30237D01*
Y-30291D01*
Y-30345D01*
Y-30400D01*
Y-30454D01*
Y-30508D01*
Y-30562D01*
Y-30616D01*
Y-30670D01*
Y-30724D01*
Y-30778D01*
Y-30832D01*
Y-30886D01*
Y-30940D01*
Y-30994D01*
Y-31048D01*
Y-31102D01*
Y-31156D01*
Y-31211D01*
Y-31265D01*
Y-31319D01*
Y-31373D01*
Y-31427D01*
Y-31481D01*
Y-31535D01*
Y-31589D01*
Y-31643D01*
Y-31697D01*
Y-31751D01*
Y-31805D01*
Y-31859D01*
Y-31913D01*
Y-31967D01*
Y-32021D01*
Y-32076D01*
Y-32129D01*
Y-32184D01*
Y-32238D01*
Y-32292D01*
Y-32346D01*
Y-32400D01*
Y-32454D01*
Y-32508D01*
Y-32562D01*
Y-32616D01*
Y-32670D01*
Y-32724D01*
Y-32778D01*
Y-32832D01*
Y-32886D01*
Y-32941D01*
Y-32994D01*
Y-33049D01*
Y-33103D01*
Y-33157D01*
Y-33211D01*
X360914D01*
Y-33265D01*
Y-33319D01*
Y-33373D01*
Y-33427D01*
X360968D01*
Y-33481D01*
Y-33535D01*
X361022D01*
Y-33589D01*
Y-33643D01*
X361076D01*
Y-33697D01*
Y-33751D01*
X361130D01*
Y-33806D01*
X361185D01*
Y-33860D01*
Y-33914D01*
X361239D01*
Y-33968D01*
X361293D01*
Y-34022D01*
X361347D01*
Y-34076D01*
X361401D01*
Y-34130D01*
X361455D01*
Y-34184D01*
X361509D01*
Y-34238D01*
X361563D01*
Y-34292D01*
X361617D01*
Y-34346D01*
X361671D01*
Y-34400D01*
X361725D01*
Y-34454D01*
X361779D01*
Y-34508D01*
X361833D01*
Y-34562D01*
X361887D01*
Y-34616D01*
X361941D01*
Y-34670D01*
X361996D01*
Y-34725D01*
X362050D01*
Y-34779D01*
X362104D01*
Y-34833D01*
X362158D01*
Y-34887D01*
X362212D01*
Y-34941D01*
X362266D01*
Y-34995D01*
X362320D01*
Y-35049D01*
X362374D01*
Y-35103D01*
X362428D01*
Y-35157D01*
X362482D01*
Y-35211D01*
X362536D01*
Y-35265D01*
X362590D01*
Y-35319D01*
X362644D01*
Y-35373D01*
X362698D01*
Y-35427D01*
X362752D01*
Y-35481D01*
X362806D01*
Y-35535D01*
X362914D01*
Y-35590D01*
X362969D01*
Y-35644D01*
X363023D01*
Y-35698D01*
X363077D01*
Y-35752D01*
X363131D01*
Y-35806D01*
X363185D01*
Y-35860D01*
X363239D01*
Y-35914D01*
X363293D01*
Y-35968D01*
X363347D01*
Y-36022D01*
X363401D01*
Y-36076D01*
X363455D01*
Y-36130D01*
X363509D01*
Y-36184D01*
X363563D01*
Y-36238D01*
X363617D01*
Y-36292D01*
X363671D01*
Y-36346D01*
X363725D01*
Y-36400D01*
X363779D01*
Y-36454D01*
X363834D01*
Y-36509D01*
X363888D01*
Y-36563D01*
X363942D01*
Y-36617D01*
X363996D01*
Y-36671D01*
X364050D01*
Y-36725D01*
X364104D01*
Y-36779D01*
X364158D01*
Y-36833D01*
X364212D01*
Y-36887D01*
X364266D01*
Y-36941D01*
X364320D01*
Y-36995D01*
X364374D01*
Y-37049D01*
X364428D01*
Y-37103D01*
X364482D01*
Y-37157D01*
X364536D01*
Y-37211D01*
X364591D01*
Y-37265D01*
X364645D01*
Y-37319D01*
X364699D01*
Y-37374D01*
X364753D01*
Y-37428D01*
X364807D01*
Y-37482D01*
X364861D01*
Y-37536D01*
X364915D01*
Y-37590D01*
X364969D01*
Y-37644D01*
X365023D01*
Y-37698D01*
X365077D01*
Y-37752D01*
X365131D01*
Y-37806D01*
X365185D01*
Y-37860D01*
X365239D01*
Y-37914D01*
X365293D01*
Y-37968D01*
X365347D01*
Y-38022D01*
X365401D01*
Y-38076D01*
X365456D01*
Y-38130D01*
X365510D01*
Y-38184D01*
X365564D01*
Y-38238D01*
X365618D01*
Y-38293D01*
X365672D01*
Y-38347D01*
X365726D01*
Y-38401D01*
X365780D01*
Y-38455D01*
X365834D01*
Y-38509D01*
X365888D01*
Y-38563D01*
X365942D01*
Y-38617D01*
X365996D01*
Y-38671D01*
X366050D01*
Y-38725D01*
X366104D01*
Y-38779D01*
X366158D01*
Y-38833D01*
X366212D01*
Y-38887D01*
X366266D01*
Y-38941D01*
X366320D01*
Y-38995D01*
X366374D01*
Y-39050D01*
X366429D01*
Y-39103D01*
X366483D01*
Y-39158D01*
X366537D01*
Y-39212D01*
X366591D01*
Y-39266D01*
X366645D01*
Y-39320D01*
X366699D01*
Y-39374D01*
X366753D01*
Y-39428D01*
X366807D01*
Y-39482D01*
X366861D01*
Y-39536D01*
X366915D01*
Y-39590D01*
X366969D01*
Y-39644D01*
X367023D01*
Y-39698D01*
X367077D01*
Y-39752D01*
X367131D01*
Y-39806D01*
X367185D01*
Y-39860D01*
X367239D01*
Y-39915D01*
X367294D01*
Y-39968D01*
X367348D01*
Y-40023D01*
X367402D01*
Y-40077D01*
X367510D01*
Y-40131D01*
X367564D01*
Y-40185D01*
X367618D01*
Y-40239D01*
X367672D01*
Y-40293D01*
X367726D01*
Y-40347D01*
X367780D01*
Y-40401D01*
X367834D01*
Y-40455D01*
X367888D01*
Y-40509D01*
X367942D01*
Y-40563D01*
X367996D01*
Y-40617D01*
X368050D01*
Y-40671D01*
X368105D01*
Y-40725D01*
X368159D01*
Y-40780D01*
X368213D01*
Y-40834D01*
X368267D01*
Y-40888D01*
X368321D01*
Y-40942D01*
X368375D01*
Y-40996D01*
X368429D01*
Y-41050D01*
X368483D01*
Y-41104D01*
X368537D01*
Y-41158D01*
X368591D01*
Y-41212D01*
X368645D01*
Y-41266D01*
X368699D01*
Y-41320D01*
X368753D01*
Y-41374D01*
X368861D01*
Y-41320D01*
X368915D01*
Y-41266D01*
X368969D01*
Y-41212D01*
X369023D01*
Y-41158D01*
X369078D01*
Y-41104D01*
X369132D01*
Y-41050D01*
X369186D01*
Y-40996D01*
X369240D01*
Y-40942D01*
X369294D01*
Y-40888D01*
X369348D01*
Y-40834D01*
Y-40780D01*
X369402D01*
Y-40725D01*
X369456D01*
Y-40671D01*
Y-40617D01*
X369510D01*
Y-40563D01*
X369564D01*
Y-40509D01*
Y-40455D01*
Y-40401D01*
Y-40347D01*
Y-40293D01*
Y-40239D01*
Y-40185D01*
Y-40131D01*
Y-40077D01*
Y-40023D01*
Y-39968D01*
Y-39915D01*
Y-39860D01*
Y-39806D01*
Y-39752D01*
Y-39698D01*
Y-39644D01*
Y-39590D01*
Y-39536D01*
Y-39482D01*
Y-39428D01*
Y-39374D01*
Y-39320D01*
Y-39266D01*
Y-39212D01*
Y-39158D01*
Y-39103D01*
Y-39050D01*
Y-38995D01*
Y-38941D01*
Y-38887D01*
Y-38833D01*
Y-38779D01*
Y-38725D01*
Y-38671D01*
Y-38617D01*
Y-38563D01*
Y-38509D01*
Y-38455D01*
Y-38401D01*
Y-38347D01*
Y-38293D01*
Y-38238D01*
Y-38184D01*
Y-38130D01*
X369510D01*
Y-38076D01*
Y-38022D01*
X369456D01*
Y-37968D01*
Y-37914D01*
X369402D01*
Y-37860D01*
X369348D01*
Y-37806D01*
Y-37752D01*
X369294D01*
Y-37698D01*
X369240D01*
Y-37644D01*
X369186D01*
Y-37590D01*
X369132D01*
Y-37536D01*
X369078D01*
Y-37482D01*
X369023D01*
Y-37428D01*
X368969D01*
Y-37374D01*
X368915D01*
Y-37319D01*
X368861D01*
Y-37265D01*
X368807D01*
Y-37211D01*
X368753D01*
Y-37157D01*
X368699D01*
Y-37103D01*
X368645D01*
Y-37049D01*
X368591D01*
Y-36995D01*
X368537D01*
Y-36941D01*
X368483D01*
Y-36887D01*
X368375D01*
Y-36833D01*
X368321D01*
Y-36779D01*
X368267D01*
Y-36725D01*
X368213D01*
Y-36671D01*
X368159D01*
Y-36617D01*
X368105D01*
Y-36563D01*
X368050D01*
Y-36509D01*
X367996D01*
Y-36454D01*
X367942D01*
Y-36400D01*
X367888D01*
Y-36346D01*
X367834D01*
Y-36292D01*
X367780D01*
Y-36238D01*
X367726D01*
Y-36184D01*
X367672D01*
Y-36130D01*
X367618D01*
Y-36076D01*
X367564D01*
Y-36022D01*
X367510D01*
Y-35968D01*
X367456D01*
Y-35914D01*
X367402D01*
Y-35860D01*
X367348D01*
Y-35806D01*
X367294D01*
Y-35752D01*
X367239D01*
Y-35698D01*
X367185D01*
Y-35644D01*
X367131D01*
Y-35590D01*
X367077D01*
Y-35535D01*
X367023D01*
Y-35481D01*
X366969D01*
Y-35427D01*
X366915D01*
Y-35373D01*
X366861D01*
Y-35319D01*
X366807D01*
Y-35265D01*
X366753D01*
Y-35211D01*
X366699D01*
Y-35157D01*
X366645D01*
Y-35103D01*
X366591D01*
Y-35049D01*
X366537D01*
Y-34995D01*
X366483D01*
Y-34941D01*
X366429D01*
Y-34887D01*
X366374D01*
Y-34833D01*
X366320D01*
Y-34779D01*
X366266D01*
Y-34725D01*
X366212D01*
Y-34670D01*
X366158D01*
Y-34616D01*
X366104D01*
Y-34562D01*
X366050D01*
Y-34508D01*
X365996D01*
Y-34454D01*
X365942D01*
Y-34400D01*
X365888D01*
Y-34346D01*
X365834D01*
Y-34292D01*
X365780D01*
Y-34238D01*
X365726D01*
Y-34184D01*
X365672D01*
Y-34130D01*
X365618D01*
Y-34076D01*
X365564D01*
Y-34022D01*
X365510D01*
Y-33968D01*
X365456D01*
Y-33914D01*
X365401D01*
Y-33860D01*
X365347D01*
Y-33806D01*
X365293D01*
Y-33751D01*
X365239D01*
Y-33697D01*
X365185D01*
Y-33643D01*
X365131D01*
Y-33589D01*
X365077D01*
Y-33535D01*
X365023D01*
Y-33481D01*
X364969D01*
Y-33427D01*
X364915D01*
Y-33373D01*
X364861D01*
Y-33319D01*
X364807D01*
Y-33265D01*
X364699D01*
Y-33211D01*
X364645D01*
Y-33157D01*
X364591D01*
Y-33103D01*
X364536D01*
Y-33049D01*
X364482D01*
Y-32994D01*
X364428D01*
Y-32941D01*
X364374D01*
Y-32886D01*
X364320D01*
Y-32832D01*
X364266D01*
Y-32778D01*
X364212D01*
Y-32724D01*
X364158D01*
Y-32670D01*
X364104D01*
Y-32616D01*
X364050D01*
Y-32562D01*
X363996D01*
Y-32508D01*
X363942D01*
Y-32454D01*
X363888D01*
Y-32400D01*
X363834D01*
Y-32346D01*
X363779D01*
Y-32292D01*
Y-32238D01*
Y-32184D01*
Y-32129D01*
Y-32076D01*
Y-32021D01*
Y-31967D01*
Y-31913D01*
Y-31859D01*
Y-31805D01*
Y-31751D01*
Y-31697D01*
Y-31643D01*
Y-31589D01*
Y-31535D01*
Y-31481D01*
Y-31427D01*
Y-31373D01*
Y-31319D01*
Y-31265D01*
Y-31211D01*
Y-31156D01*
Y-31102D01*
Y-31048D01*
Y-30994D01*
Y-30940D01*
Y-30886D01*
Y-30832D01*
Y-30778D01*
Y-30724D01*
Y-30670D01*
Y-30616D01*
Y-30562D01*
Y-30508D01*
Y-30454D01*
Y-30400D01*
Y-30345D01*
Y-30291D01*
Y-30237D01*
Y-30183D01*
Y-30129D01*
Y-30075D01*
Y-30021D01*
Y-29967D01*
Y-29913D01*
Y-29859D01*
Y-29805D01*
Y-29751D01*
Y-29697D01*
Y-29643D01*
Y-29589D01*
Y-29535D01*
Y-29480D01*
Y-29426D01*
Y-29372D01*
Y-29318D01*
Y-29264D01*
Y-29210D01*
Y-29156D01*
Y-29102D01*
Y-29048D01*
Y-28994D01*
Y-28940D01*
Y-28886D01*
Y-28832D01*
Y-28778D01*
Y-28724D01*
Y-28670D01*
Y-28615D01*
Y-28561D01*
Y-28507D01*
Y-28453D01*
Y-28399D01*
Y-28345D01*
Y-28291D01*
Y-28237D01*
Y-28183D01*
Y-28129D01*
Y-28075D01*
Y-28021D01*
Y-27967D01*
Y-27913D01*
Y-27859D01*
Y-27805D01*
Y-27751D01*
Y-27696D01*
Y-27642D01*
Y-27588D01*
Y-27534D01*
Y-27480D01*
Y-27426D01*
Y-27372D01*
Y-27318D01*
Y-27264D01*
Y-27210D01*
Y-27156D01*
Y-27102D01*
Y-27048D01*
Y-26994D01*
Y-26940D01*
Y-26886D01*
Y-26831D01*
Y-26777D01*
Y-26723D01*
Y-26669D01*
Y-26615D01*
Y-26561D01*
Y-26507D01*
Y-26453D01*
Y-26399D01*
Y-26345D01*
Y-26291D01*
Y-26237D01*
Y-26183D01*
Y-26129D01*
Y-26075D01*
Y-26021D01*
Y-25967D01*
Y-25912D01*
Y-25858D01*
Y-25804D01*
Y-25750D01*
Y-25696D01*
Y-25642D01*
Y-25588D01*
Y-25534D01*
Y-25480D01*
Y-25426D01*
Y-25372D01*
Y-25318D01*
Y-25264D01*
Y-25210D01*
Y-25155D01*
Y-25102D01*
Y-25047D01*
Y-24993D01*
Y-24939D01*
Y-24885D01*
Y-24831D01*
Y-24777D01*
Y-24723D01*
Y-24669D01*
Y-24615D01*
Y-24561D01*
Y-24507D01*
Y-24453D01*
Y-24399D01*
Y-24345D01*
Y-24291D01*
Y-24237D01*
Y-24182D01*
Y-24128D01*
Y-24074D01*
Y-24020D01*
Y-23966D01*
Y-23912D01*
Y-23858D01*
Y-23804D01*
Y-23750D01*
Y-23696D01*
Y-23642D01*
Y-23588D01*
Y-23534D01*
Y-23480D01*
Y-23426D01*
Y-23371D01*
Y-23317D01*
Y-23263D01*
Y-23209D01*
Y-23155D01*
Y-23101D01*
Y-23047D01*
Y-22993D01*
Y-22939D01*
Y-22885D01*
Y-22831D01*
Y-22777D01*
Y-22723D01*
Y-22669D01*
Y-22615D01*
Y-22561D01*
Y-22506D01*
Y-22452D01*
Y-22398D01*
Y-22344D01*
Y-22290D01*
Y-22236D01*
Y-22182D01*
Y-22128D01*
Y-22074D01*
Y-22020D01*
Y-21966D01*
Y-21912D01*
Y-21858D01*
Y-21804D01*
Y-21750D01*
Y-21696D01*
Y-21642D01*
Y-21587D01*
Y-21533D01*
Y-21479D01*
Y-21425D01*
Y-21371D01*
Y-21317D01*
Y-21263D01*
Y-21209D01*
Y-21155D01*
Y-21101D01*
Y-21047D01*
Y-20993D01*
Y-20939D01*
Y-20885D01*
Y-20831D01*
Y-20776D01*
Y-20722D01*
Y-20668D01*
Y-20614D01*
Y-20560D01*
Y-20506D01*
Y-20452D01*
Y-20398D01*
Y-20344D01*
Y-20290D01*
Y-20236D01*
Y-20182D01*
Y-20128D01*
Y-20074D01*
Y-20020D01*
Y-19966D01*
Y-19911D01*
Y-19858D01*
Y-19803D01*
Y-19749D01*
Y-19695D01*
Y-19641D01*
Y-19587D01*
Y-19533D01*
Y-19479D01*
Y-19425D01*
Y-19371D01*
Y-19317D01*
Y-19263D01*
Y-19209D01*
Y-19155D01*
Y-19101D01*
Y-19047D01*
Y-18993D01*
Y-18938D01*
Y-18884D01*
Y-18830D01*
Y-18776D01*
Y-18722D01*
Y-18668D01*
Y-18614D01*
Y-18560D01*
Y-18506D01*
Y-18452D01*
Y-18398D01*
Y-18344D01*
Y-18290D01*
Y-18236D01*
Y-18181D01*
Y-18127D01*
Y-18073D01*
Y-18019D01*
Y-17965D01*
Y-17911D01*
Y-17857D01*
Y-17803D01*
Y-17749D01*
Y-17695D01*
Y-17641D01*
Y-17587D01*
Y-17533D01*
Y-17479D01*
Y-17425D01*
Y-17371D01*
Y-17317D01*
Y-17263D01*
Y-17208D01*
Y-17154D01*
Y-17100D01*
Y-17046D01*
Y-16992D01*
Y-16938D01*
Y-16884D01*
Y-16830D01*
Y-16776D01*
Y-16722D01*
Y-16668D01*
Y-16614D01*
Y-16560D01*
Y-16506D01*
Y-16452D01*
Y-16398D01*
Y-16343D01*
Y-16289D01*
Y-16235D01*
Y-16181D01*
Y-16127D01*
Y-16073D01*
Y-16019D01*
Y-15965D01*
Y-15911D01*
Y-15857D01*
Y-15803D01*
Y-15749D01*
Y-15695D01*
Y-15641D01*
Y-15587D01*
Y-15532D01*
Y-15478D01*
Y-15424D01*
Y-15370D01*
Y-15316D01*
Y-15262D01*
Y-15208D01*
Y-15154D01*
Y-15100D01*
Y-15046D01*
Y-14992D01*
Y-14938D01*
Y-14884D01*
Y-14830D01*
Y-14776D01*
Y-14722D01*
Y-14668D01*
Y-14614D01*
Y-14559D01*
Y-14505D01*
Y-14451D01*
D02*
G37*
G36*
X359833Y-33643D02*
X359076D01*
Y-33697D01*
X358860D01*
Y-33751D01*
X358752D01*
Y-33806D01*
X358644D01*
Y-33860D01*
X358590D01*
Y-33914D01*
X358536D01*
Y-33968D01*
X358481D01*
Y-34022D01*
X358427D01*
Y-34076D01*
X358373D01*
Y-34130D01*
X358319D01*
Y-34184D01*
X358265D01*
Y-34238D01*
X358211D01*
Y-34292D01*
X358157D01*
Y-34346D01*
X358103D01*
Y-34400D01*
X358049D01*
Y-34454D01*
X357995D01*
Y-34508D01*
X357941D01*
Y-34562D01*
X357887D01*
Y-34616D01*
X357833D01*
Y-34670D01*
X357779D01*
Y-34725D01*
X357725D01*
Y-34779D01*
X357670D01*
Y-34833D01*
X357616D01*
Y-34887D01*
X357562D01*
Y-34941D01*
X357508D01*
Y-34995D01*
X357454D01*
Y-35049D01*
X357400D01*
Y-35103D01*
X357346D01*
Y-35157D01*
X357292D01*
Y-35211D01*
X357238D01*
Y-35265D01*
X357184D01*
Y-35319D01*
X357130D01*
Y-35373D01*
Y-35427D01*
Y-35481D01*
X357076D01*
Y-35535D01*
Y-35590D01*
Y-35644D01*
Y-35698D01*
X357022D01*
Y-35752D01*
Y-35806D01*
Y-35860D01*
Y-35914D01*
Y-35968D01*
Y-36022D01*
Y-36076D01*
Y-36130D01*
Y-36184D01*
Y-36238D01*
Y-36292D01*
Y-36346D01*
Y-36400D01*
Y-36454D01*
Y-36509D01*
Y-36563D01*
Y-36617D01*
Y-36671D01*
Y-36725D01*
Y-36779D01*
Y-36833D01*
Y-36887D01*
Y-36941D01*
Y-36995D01*
Y-37049D01*
Y-37103D01*
Y-37157D01*
Y-37211D01*
Y-37265D01*
Y-37319D01*
Y-37374D01*
Y-37428D01*
Y-37482D01*
Y-37536D01*
Y-37590D01*
Y-37644D01*
Y-37698D01*
Y-37752D01*
Y-37806D01*
Y-37860D01*
Y-37914D01*
Y-37968D01*
Y-38022D01*
Y-38076D01*
Y-38130D01*
Y-38184D01*
Y-38238D01*
Y-38293D01*
Y-38347D01*
Y-38401D01*
Y-38455D01*
Y-38509D01*
Y-38563D01*
Y-38617D01*
Y-38671D01*
Y-38725D01*
Y-38779D01*
Y-38833D01*
Y-38887D01*
Y-38941D01*
Y-38995D01*
Y-39050D01*
Y-39103D01*
Y-39158D01*
Y-39212D01*
Y-39266D01*
Y-39320D01*
Y-39374D01*
Y-39428D01*
Y-39482D01*
Y-39536D01*
Y-39590D01*
Y-39644D01*
Y-39698D01*
Y-39752D01*
Y-39806D01*
Y-39860D01*
Y-39915D01*
Y-39968D01*
Y-40023D01*
Y-40077D01*
Y-40131D01*
Y-40185D01*
Y-40239D01*
Y-40293D01*
Y-40347D01*
Y-40401D01*
Y-40455D01*
Y-40509D01*
Y-40563D01*
Y-40617D01*
Y-40671D01*
Y-40725D01*
Y-40780D01*
Y-40834D01*
Y-40888D01*
Y-40942D01*
Y-40996D01*
Y-41050D01*
Y-41104D01*
Y-41158D01*
Y-41212D01*
Y-41266D01*
Y-41320D01*
Y-41374D01*
Y-41428D01*
Y-41482D01*
Y-41536D01*
Y-41590D01*
Y-41644D01*
Y-41699D01*
Y-41753D01*
Y-41807D01*
Y-41861D01*
Y-41915D01*
Y-41969D01*
Y-42023D01*
Y-42077D01*
Y-42131D01*
Y-42185D01*
Y-42239D01*
Y-42293D01*
Y-42347D01*
Y-42401D01*
Y-42455D01*
Y-42509D01*
Y-42564D01*
Y-42618D01*
Y-42672D01*
Y-42726D01*
Y-42780D01*
Y-42834D01*
Y-42888D01*
Y-42942D01*
Y-42996D01*
Y-43050D01*
Y-43104D01*
Y-43158D01*
Y-43212D01*
Y-43266D01*
Y-43320D01*
Y-43374D01*
Y-43429D01*
Y-43483D01*
Y-43537D01*
Y-43591D01*
Y-43645D01*
Y-43699D01*
Y-43753D01*
Y-43807D01*
Y-43861D01*
Y-43915D01*
Y-43969D01*
Y-44023D01*
Y-44077D01*
Y-44131D01*
Y-44185D01*
Y-44239D01*
Y-44293D01*
Y-44348D01*
Y-44402D01*
Y-44456D01*
Y-44510D01*
Y-44564D01*
Y-44618D01*
Y-44672D01*
Y-44726D01*
Y-44780D01*
Y-44834D01*
Y-44888D01*
Y-44942D01*
Y-44996D01*
Y-45050D01*
Y-45104D01*
Y-45158D01*
Y-45213D01*
X357076D01*
Y-45267D01*
Y-45321D01*
X357130D01*
Y-45375D01*
X357238D01*
Y-45429D01*
X359779D01*
Y-45375D01*
X359887D01*
Y-45321D01*
X359941D01*
Y-45267D01*
X359995D01*
Y-45213D01*
Y-45158D01*
Y-45104D01*
Y-45050D01*
Y-44996D01*
Y-44942D01*
Y-44888D01*
Y-44834D01*
Y-44780D01*
Y-44726D01*
Y-44672D01*
Y-44618D01*
Y-44564D01*
Y-44510D01*
Y-44456D01*
Y-44402D01*
Y-44348D01*
Y-44293D01*
Y-44239D01*
Y-44185D01*
Y-44131D01*
Y-44077D01*
Y-44023D01*
Y-43969D01*
Y-43915D01*
Y-43861D01*
Y-43807D01*
Y-43753D01*
Y-43699D01*
Y-43645D01*
Y-43591D01*
Y-43537D01*
Y-43483D01*
Y-43429D01*
Y-43374D01*
Y-43320D01*
Y-43266D01*
Y-43212D01*
Y-43158D01*
Y-43104D01*
Y-43050D01*
Y-42996D01*
Y-42942D01*
Y-42888D01*
Y-42834D01*
Y-42780D01*
Y-42726D01*
Y-42672D01*
Y-42618D01*
Y-42564D01*
Y-42509D01*
Y-42455D01*
Y-42401D01*
Y-42347D01*
Y-42293D01*
Y-42239D01*
Y-42185D01*
Y-42131D01*
Y-42077D01*
Y-42023D01*
Y-41969D01*
X360049D01*
Y-41915D01*
Y-41861D01*
X360157D01*
Y-41807D01*
X363779D01*
Y-41861D01*
X363888D01*
Y-41915D01*
Y-41969D01*
X363942D01*
Y-42023D01*
Y-42077D01*
Y-42131D01*
Y-42185D01*
Y-42239D01*
Y-42293D01*
Y-42347D01*
Y-42401D01*
Y-42455D01*
Y-42509D01*
Y-42564D01*
Y-42618D01*
Y-42672D01*
Y-42726D01*
Y-42780D01*
Y-42834D01*
Y-42888D01*
Y-42942D01*
Y-42996D01*
Y-43050D01*
Y-43104D01*
Y-43158D01*
Y-43212D01*
Y-43266D01*
Y-43320D01*
Y-43374D01*
Y-43429D01*
Y-43483D01*
Y-43537D01*
Y-43591D01*
Y-43645D01*
Y-43699D01*
Y-43753D01*
Y-43807D01*
Y-43861D01*
Y-43915D01*
Y-43969D01*
Y-44023D01*
Y-44077D01*
Y-44131D01*
Y-44185D01*
Y-44239D01*
Y-44293D01*
Y-44348D01*
Y-44402D01*
Y-44456D01*
Y-44510D01*
Y-44564D01*
Y-44618D01*
Y-44672D01*
Y-44726D01*
Y-44780D01*
Y-44834D01*
Y-44888D01*
Y-44942D01*
Y-44996D01*
Y-45050D01*
Y-45104D01*
Y-45158D01*
Y-45213D01*
X363996D01*
Y-45267D01*
Y-45321D01*
X364050D01*
Y-45375D01*
X364158D01*
Y-45429D01*
X366699D01*
Y-45375D01*
X366807D01*
Y-45321D01*
X366861D01*
Y-45267D01*
X366915D01*
Y-45213D01*
Y-45158D01*
Y-45104D01*
Y-45050D01*
Y-44996D01*
Y-44942D01*
Y-44888D01*
Y-44834D01*
Y-44780D01*
Y-44726D01*
Y-44672D01*
Y-44618D01*
Y-44564D01*
Y-44510D01*
Y-44456D01*
Y-44402D01*
Y-44348D01*
Y-44293D01*
Y-44239D01*
Y-44185D01*
Y-44131D01*
Y-44077D01*
Y-44023D01*
Y-43969D01*
Y-43915D01*
Y-43861D01*
Y-43807D01*
Y-43753D01*
Y-43699D01*
Y-43645D01*
Y-43591D01*
Y-43537D01*
Y-43483D01*
Y-43429D01*
Y-43374D01*
Y-43320D01*
Y-43266D01*
Y-43212D01*
Y-43158D01*
Y-43104D01*
Y-43050D01*
Y-42996D01*
Y-42942D01*
Y-42888D01*
Y-42834D01*
Y-42780D01*
Y-42726D01*
Y-42672D01*
Y-42618D01*
Y-42564D01*
Y-42509D01*
Y-42455D01*
Y-42401D01*
Y-42347D01*
Y-42293D01*
Y-42239D01*
Y-42185D01*
Y-42131D01*
Y-42077D01*
Y-42023D01*
Y-41969D01*
Y-41915D01*
Y-41861D01*
Y-41807D01*
Y-41753D01*
Y-41699D01*
Y-41644D01*
Y-41590D01*
Y-41536D01*
Y-41482D01*
Y-41428D01*
Y-41374D01*
Y-41320D01*
Y-41266D01*
Y-41212D01*
Y-41158D01*
Y-41104D01*
Y-41050D01*
Y-40996D01*
Y-40942D01*
X366861D01*
Y-40888D01*
X366807D01*
Y-40834D01*
X366753D01*
Y-40780D01*
X366699D01*
Y-40725D01*
X366645D01*
Y-40671D01*
X366591D01*
Y-40617D01*
X366483D01*
Y-40563D01*
X366429D01*
Y-40509D01*
X366374D01*
Y-40455D01*
X366320D01*
Y-40401D01*
X366266D01*
Y-40347D01*
X366212D01*
Y-40293D01*
X366158D01*
Y-40239D01*
X366104D01*
Y-40185D01*
X366050D01*
Y-40131D01*
X365996D01*
Y-40077D01*
X365942D01*
Y-40023D01*
X365888D01*
Y-39968D01*
X365834D01*
Y-39915D01*
X365780D01*
Y-39860D01*
X365726D01*
Y-39806D01*
X365672D01*
Y-39752D01*
X365618D01*
Y-39698D01*
X365564D01*
Y-39644D01*
X365510D01*
Y-39590D01*
X365456D01*
Y-39536D01*
X365401D01*
Y-39482D01*
X365347D01*
Y-39428D01*
X365293D01*
Y-39374D01*
X365239D01*
Y-39320D01*
X365185D01*
Y-39266D01*
X365131D01*
Y-39212D01*
X365077D01*
Y-39158D01*
X365023D01*
Y-39103D01*
X364969D01*
Y-39050D01*
X364915D01*
Y-38995D01*
X364861D01*
Y-38941D01*
X364807D01*
Y-38887D01*
X364753D01*
Y-38833D01*
X364699D01*
Y-38779D01*
X364645D01*
Y-38725D01*
X364591D01*
Y-38671D01*
X364536D01*
Y-38617D01*
X364482D01*
Y-38563D01*
X364428D01*
Y-38509D01*
X364374D01*
Y-38455D01*
X364320D01*
Y-38401D01*
X364266D01*
Y-38347D01*
X364212D01*
Y-38293D01*
X364158D01*
Y-38238D01*
X364104D01*
Y-38184D01*
X364050D01*
Y-38130D01*
X363996D01*
Y-38076D01*
X363942D01*
Y-38130D01*
Y-38184D01*
Y-38238D01*
Y-38293D01*
Y-38347D01*
Y-38401D01*
Y-38455D01*
Y-38509D01*
Y-38563D01*
Y-38617D01*
Y-38671D01*
Y-38725D01*
Y-38779D01*
Y-38833D01*
Y-38887D01*
Y-38941D01*
Y-38995D01*
Y-39050D01*
Y-39103D01*
Y-39158D01*
Y-39212D01*
Y-39266D01*
X359995D01*
Y-39212D01*
Y-39158D01*
Y-39103D01*
Y-39050D01*
Y-38995D01*
Y-38941D01*
Y-38887D01*
Y-38833D01*
Y-38779D01*
Y-38725D01*
Y-38671D01*
Y-38617D01*
Y-38563D01*
Y-38509D01*
Y-38455D01*
Y-38401D01*
Y-38347D01*
Y-38293D01*
Y-38238D01*
Y-38184D01*
Y-38130D01*
Y-38076D01*
Y-38022D01*
Y-37968D01*
Y-37914D01*
Y-37860D01*
Y-37806D01*
Y-37752D01*
Y-37698D01*
Y-37644D01*
Y-37590D01*
Y-37536D01*
Y-37482D01*
Y-37428D01*
Y-37374D01*
Y-37319D01*
Y-37265D01*
Y-37211D01*
Y-37157D01*
Y-37103D01*
Y-37049D01*
Y-36995D01*
Y-36941D01*
Y-36887D01*
Y-36833D01*
Y-36779D01*
Y-36725D01*
Y-36671D01*
Y-36617D01*
Y-36563D01*
Y-36509D01*
Y-36454D01*
Y-36400D01*
Y-36346D01*
Y-36292D01*
X362428D01*
Y-36238D01*
X362374D01*
Y-36184D01*
X362320D01*
Y-36130D01*
X362266D01*
Y-36076D01*
X362212D01*
Y-36022D01*
X362158D01*
Y-35968D01*
X362104D01*
Y-35914D01*
X362050D01*
Y-35860D01*
X361996D01*
Y-35806D01*
X361941D01*
Y-35752D01*
X361887D01*
Y-35698D01*
X361833D01*
Y-35644D01*
X361779D01*
Y-35590D01*
X361725D01*
Y-35535D01*
X361671D01*
Y-35481D01*
X361617D01*
Y-35427D01*
X361563D01*
Y-35373D01*
X361509D01*
Y-35319D01*
X361455D01*
Y-35265D01*
X361401D01*
Y-35211D01*
X361347D01*
Y-35157D01*
X361293D01*
Y-35103D01*
X361239D01*
Y-35049D01*
X361185D01*
Y-34995D01*
X361130D01*
Y-34941D01*
X361076D01*
Y-34887D01*
X361022D01*
Y-34833D01*
X360968D01*
Y-34779D01*
X360914D01*
Y-34725D01*
X360860D01*
Y-34670D01*
X360806D01*
Y-34616D01*
X360752D01*
Y-34562D01*
X360698D01*
Y-34508D01*
X360644D01*
Y-34454D01*
X360590D01*
Y-34400D01*
X360536D01*
Y-34346D01*
X360482D01*
Y-34292D01*
X360428D01*
Y-34238D01*
X360374D01*
Y-34184D01*
X360320D01*
Y-34130D01*
X360265D01*
Y-34076D01*
X360211D01*
Y-34022D01*
X360157D01*
Y-33968D01*
X360103D01*
Y-33914D01*
X360049D01*
Y-33860D01*
X359995D01*
Y-33806D01*
X359941D01*
Y-33751D01*
X359887D01*
Y-33697D01*
X359833D01*
Y-33643D01*
D02*
G37*
G36*
X355616D02*
X348156D01*
Y-33697D01*
X347885D01*
Y-33751D01*
X347723D01*
Y-33806D01*
X347615D01*
Y-33860D01*
X347561D01*
Y-33914D01*
X347507D01*
Y-33968D01*
X347453D01*
Y-34022D01*
X347399D01*
Y-34076D01*
X347345D01*
Y-34130D01*
X347291D01*
Y-34184D01*
X347236D01*
Y-34238D01*
X347182D01*
Y-34292D01*
X347128D01*
Y-34346D01*
X347074D01*
Y-34400D01*
X347020D01*
Y-34454D01*
X346966D01*
Y-34508D01*
X346912D01*
Y-34562D01*
X346858D01*
Y-34616D01*
X346804D01*
Y-34670D01*
X346750D01*
Y-34725D01*
X346696D01*
Y-34779D01*
X346642D01*
Y-34833D01*
X346588D01*
Y-34887D01*
X346534D01*
Y-34941D01*
X346480D01*
Y-34995D01*
X346426D01*
Y-35049D01*
X346372D01*
Y-35103D01*
X346318D01*
Y-35157D01*
X346263D01*
Y-35211D01*
X346209D01*
Y-35265D01*
X346155D01*
Y-35319D01*
X346101D01*
Y-35373D01*
Y-35427D01*
X346047D01*
Y-35481D01*
Y-35535D01*
Y-35590D01*
X345993D01*
Y-35644D01*
Y-35698D01*
Y-35752D01*
Y-35806D01*
Y-35860D01*
Y-35914D01*
Y-35968D01*
Y-36022D01*
Y-36076D01*
Y-36130D01*
Y-36184D01*
Y-36238D01*
Y-36292D01*
Y-36346D01*
Y-36400D01*
Y-36454D01*
Y-36509D01*
Y-36563D01*
Y-36617D01*
Y-36671D01*
Y-36725D01*
Y-36779D01*
Y-36833D01*
Y-36887D01*
Y-36941D01*
Y-36995D01*
Y-37049D01*
Y-37103D01*
Y-37157D01*
Y-37211D01*
Y-37265D01*
Y-37319D01*
Y-37374D01*
Y-37428D01*
Y-37482D01*
Y-37536D01*
Y-37590D01*
Y-37644D01*
Y-37698D01*
Y-37752D01*
Y-37806D01*
Y-37860D01*
Y-37914D01*
Y-37968D01*
Y-38022D01*
Y-38076D01*
Y-38130D01*
Y-38184D01*
Y-38238D01*
Y-38293D01*
Y-38347D01*
Y-38401D01*
Y-38455D01*
Y-38509D01*
Y-38563D01*
Y-38617D01*
Y-38671D01*
Y-38725D01*
Y-38779D01*
Y-38833D01*
Y-38887D01*
Y-38941D01*
Y-38995D01*
Y-39050D01*
Y-39103D01*
Y-39158D01*
Y-39212D01*
Y-39266D01*
Y-39320D01*
Y-39374D01*
Y-39428D01*
Y-39482D01*
Y-39536D01*
Y-39590D01*
Y-39644D01*
Y-39698D01*
Y-39752D01*
Y-39806D01*
Y-39860D01*
X346047D01*
Y-39915D01*
Y-39968D01*
X346101D01*
Y-40023D01*
Y-40077D01*
X346155D01*
Y-40131D01*
X346209D01*
Y-40185D01*
X346263D01*
Y-40239D01*
X346318D01*
Y-40293D01*
X346372D01*
Y-40347D01*
X346426D01*
Y-40401D01*
Y-40455D01*
X346480D01*
Y-40509D01*
X346534D01*
Y-40563D01*
X346588D01*
Y-40617D01*
X346642D01*
Y-40671D01*
X346696D01*
Y-40725D01*
X346750D01*
Y-40780D01*
X346804D01*
Y-40834D01*
X346858D01*
Y-40888D01*
X346912D01*
Y-40942D01*
X346966D01*
Y-40996D01*
X347020D01*
Y-41050D01*
X347074D01*
Y-41104D01*
X347128D01*
Y-41158D01*
X347182D01*
Y-41212D01*
X347236D01*
Y-41266D01*
X347291D01*
Y-41320D01*
X347345D01*
Y-41374D01*
X347399D01*
Y-41428D01*
X347453D01*
Y-41482D01*
X347507D01*
Y-41536D01*
X347561D01*
Y-41590D01*
X347615D01*
Y-41644D01*
X347669D01*
Y-41699D01*
Y-41753D01*
X347615D01*
Y-41807D01*
X347561D01*
Y-41861D01*
Y-41915D01*
X347507D01*
Y-41969D01*
Y-42023D01*
X347453D01*
Y-42077D01*
X347399D01*
Y-42131D01*
Y-42185D01*
X347345D01*
Y-42239D01*
Y-42293D01*
X347291D01*
Y-42347D01*
Y-42401D01*
X347236D01*
Y-42455D01*
X347182D01*
Y-42509D01*
Y-42564D01*
X347128D01*
Y-42618D01*
Y-42672D01*
X347074D01*
Y-42726D01*
X347020D01*
Y-42780D01*
Y-42834D01*
X346966D01*
Y-42888D01*
Y-42942D01*
X346912D01*
Y-42996D01*
X346858D01*
Y-43050D01*
Y-43104D01*
X346804D01*
Y-43158D01*
Y-43212D01*
X346750D01*
Y-43266D01*
X346696D01*
Y-43320D01*
Y-43374D01*
X346642D01*
Y-43429D01*
Y-43483D01*
X346588D01*
Y-43537D01*
X346534D01*
Y-43591D01*
Y-43645D01*
X346480D01*
Y-43699D01*
Y-43753D01*
X346426D01*
Y-43807D01*
X346372D01*
Y-43861D01*
Y-43915D01*
X346318D01*
Y-43969D01*
Y-44023D01*
X346263D01*
Y-44077D01*
X346209D01*
Y-44131D01*
Y-44185D01*
X346155D01*
Y-44239D01*
Y-44293D01*
X346101D01*
Y-44348D01*
X346047D01*
Y-44402D01*
Y-44456D01*
X345993D01*
Y-44510D01*
Y-44564D01*
X345939D01*
Y-44618D01*
X345885D01*
Y-44672D01*
Y-44726D01*
X345831D01*
Y-44780D01*
Y-44834D01*
X345777D01*
Y-44888D01*
X345723D01*
Y-44942D01*
Y-44996D01*
X345669D01*
Y-45050D01*
Y-45104D01*
X345615D01*
Y-45158D01*
X345561D01*
Y-45213D01*
Y-45267D01*
Y-45321D01*
Y-45375D01*
X345615D01*
Y-45429D01*
X348642D01*
Y-45375D01*
X348750D01*
Y-45321D01*
X348804D01*
Y-45267D01*
X348858D01*
Y-45213D01*
X348913D01*
Y-45158D01*
X348967D01*
Y-45104D01*
Y-45050D01*
X349021D01*
Y-44996D01*
Y-44942D01*
X349075D01*
Y-44888D01*
X349129D01*
Y-44834D01*
Y-44780D01*
X349183D01*
Y-44726D01*
Y-44672D01*
X349237D01*
Y-44618D01*
Y-44564D01*
X349291D01*
Y-44510D01*
X349345D01*
Y-44456D01*
Y-44402D01*
X349399D01*
Y-44348D01*
Y-44293D01*
X349453D01*
Y-44239D01*
X349507D01*
Y-44185D01*
Y-44131D01*
X349561D01*
Y-44077D01*
Y-44023D01*
X349615D01*
Y-43969D01*
X349669D01*
Y-43915D01*
Y-43861D01*
X349723D01*
Y-43807D01*
Y-43753D01*
X349778D01*
Y-43699D01*
X349832D01*
Y-43645D01*
Y-43591D01*
X349886D01*
Y-43537D01*
Y-43483D01*
X349940D01*
Y-43429D01*
Y-43374D01*
X349994D01*
Y-43320D01*
X350048D01*
Y-43266D01*
Y-43212D01*
X350102D01*
Y-43158D01*
Y-43104D01*
X350156D01*
Y-43050D01*
X350210D01*
Y-42996D01*
Y-42942D01*
X350264D01*
Y-42888D01*
Y-42834D01*
X350318D01*
Y-42780D01*
X350372D01*
Y-42726D01*
Y-42672D01*
X350426D01*
Y-42618D01*
Y-42564D01*
X350480D01*
Y-42509D01*
Y-42455D01*
X350534D01*
Y-42401D01*
X350588D01*
Y-42347D01*
Y-42293D01*
X350642D01*
Y-42239D01*
Y-42185D01*
X350696D01*
Y-42131D01*
X350751D01*
Y-42077D01*
Y-42023D01*
X350805D01*
Y-41969D01*
Y-41915D01*
X352859D01*
Y-41969D01*
Y-42023D01*
Y-42077D01*
Y-42131D01*
Y-42185D01*
X352913D01*
Y-42239D01*
X352859D01*
Y-42293D01*
Y-42347D01*
Y-42401D01*
Y-42455D01*
Y-42509D01*
Y-42564D01*
Y-42618D01*
Y-42672D01*
Y-42726D01*
Y-42780D01*
Y-42834D01*
Y-42888D01*
Y-42942D01*
Y-42996D01*
Y-43050D01*
Y-43104D01*
Y-43158D01*
Y-43212D01*
Y-43266D01*
Y-43320D01*
Y-43374D01*
Y-43429D01*
Y-43483D01*
Y-43537D01*
Y-43591D01*
Y-43645D01*
Y-43699D01*
Y-43753D01*
Y-43807D01*
Y-43861D01*
Y-43915D01*
Y-43969D01*
Y-44023D01*
Y-44077D01*
Y-44131D01*
Y-44185D01*
Y-44239D01*
Y-44293D01*
Y-44348D01*
Y-44402D01*
Y-44456D01*
Y-44510D01*
Y-44564D01*
Y-44618D01*
Y-44672D01*
Y-44726D01*
Y-44780D01*
Y-44834D01*
Y-44888D01*
Y-44942D01*
Y-44996D01*
Y-45050D01*
Y-45104D01*
Y-45158D01*
X352913D01*
Y-45213D01*
Y-45267D01*
Y-45321D01*
X352967D01*
Y-45375D01*
X353021D01*
Y-45429D01*
X355670D01*
Y-45375D01*
X355778D01*
Y-45321D01*
X355832D01*
Y-45267D01*
Y-45213D01*
Y-45158D01*
X355887D01*
Y-45104D01*
X355832D01*
Y-45050D01*
X355887D01*
Y-44996D01*
Y-44942D01*
Y-44888D01*
Y-44834D01*
Y-44780D01*
Y-44726D01*
Y-44672D01*
Y-44618D01*
Y-44564D01*
Y-44510D01*
Y-44456D01*
Y-44402D01*
Y-44348D01*
Y-44293D01*
Y-44239D01*
Y-44185D01*
Y-44131D01*
Y-44077D01*
Y-44023D01*
Y-43969D01*
Y-43915D01*
Y-43861D01*
Y-43807D01*
Y-43753D01*
Y-43699D01*
Y-43645D01*
Y-43591D01*
Y-43537D01*
Y-43483D01*
Y-43429D01*
Y-43374D01*
Y-43320D01*
Y-43266D01*
Y-43212D01*
Y-43158D01*
Y-43104D01*
Y-43050D01*
Y-42996D01*
Y-42942D01*
Y-42888D01*
Y-42834D01*
Y-42780D01*
Y-42726D01*
Y-42672D01*
Y-42618D01*
Y-42564D01*
Y-42509D01*
Y-42455D01*
Y-42401D01*
Y-42347D01*
Y-42293D01*
Y-42239D01*
Y-42185D01*
Y-42131D01*
Y-42077D01*
Y-42023D01*
Y-41969D01*
Y-41915D01*
Y-41861D01*
Y-41807D01*
Y-41753D01*
Y-41699D01*
Y-41644D01*
Y-41590D01*
Y-41536D01*
Y-41482D01*
Y-41428D01*
Y-41374D01*
Y-41320D01*
Y-41266D01*
Y-41212D01*
Y-41158D01*
Y-41104D01*
Y-41050D01*
Y-40996D01*
Y-40942D01*
Y-40888D01*
Y-40834D01*
Y-40780D01*
Y-40725D01*
Y-40671D01*
Y-40617D01*
Y-40563D01*
Y-40509D01*
Y-40455D01*
Y-40401D01*
Y-40347D01*
Y-40293D01*
Y-40239D01*
Y-40185D01*
Y-40131D01*
Y-40077D01*
Y-40023D01*
Y-39968D01*
Y-39915D01*
Y-39860D01*
Y-39806D01*
Y-39752D01*
Y-39698D01*
Y-39644D01*
Y-39590D01*
Y-39536D01*
Y-39482D01*
Y-39428D01*
Y-39374D01*
Y-39320D01*
Y-39266D01*
Y-39212D01*
Y-39158D01*
Y-39103D01*
Y-39050D01*
Y-38995D01*
Y-38941D01*
Y-38887D01*
Y-38833D01*
Y-38779D01*
Y-38725D01*
Y-38671D01*
Y-38617D01*
Y-38563D01*
Y-38509D01*
Y-38455D01*
Y-38401D01*
Y-38347D01*
Y-38293D01*
Y-38238D01*
Y-38184D01*
Y-38130D01*
Y-38076D01*
Y-38022D01*
Y-37968D01*
Y-37914D01*
Y-37860D01*
Y-37806D01*
Y-37752D01*
Y-37698D01*
Y-37644D01*
Y-37590D01*
Y-37536D01*
Y-37482D01*
Y-37428D01*
Y-37374D01*
Y-37319D01*
Y-37265D01*
Y-37211D01*
Y-37157D01*
Y-37103D01*
Y-37049D01*
Y-36995D01*
Y-36941D01*
Y-36887D01*
Y-36833D01*
Y-36779D01*
Y-36725D01*
Y-36671D01*
Y-36617D01*
Y-36563D01*
Y-36509D01*
Y-36454D01*
Y-36400D01*
Y-36346D01*
Y-36292D01*
Y-36238D01*
Y-36184D01*
Y-36130D01*
Y-36076D01*
Y-36022D01*
Y-35968D01*
Y-35914D01*
Y-35860D01*
Y-35806D01*
Y-35752D01*
Y-35698D01*
Y-35644D01*
Y-35590D01*
Y-35535D01*
Y-35481D01*
Y-35427D01*
Y-35373D01*
Y-35319D01*
Y-35265D01*
Y-35211D01*
Y-35157D01*
Y-35103D01*
Y-35049D01*
Y-34995D01*
Y-34941D01*
Y-34887D01*
Y-34833D01*
Y-34779D01*
Y-34725D01*
Y-34670D01*
Y-34616D01*
Y-34562D01*
Y-34508D01*
Y-34454D01*
Y-34400D01*
Y-34346D01*
Y-34292D01*
Y-34238D01*
Y-34184D01*
Y-34130D01*
Y-34076D01*
Y-34022D01*
Y-33968D01*
X355832D01*
Y-33914D01*
Y-33860D01*
Y-33806D01*
X355778D01*
Y-33751D01*
X355724D01*
Y-33697D01*
X355616D01*
Y-33643D01*
D02*
G37*
G36*
X344101D02*
X336640D01*
Y-33697D01*
X336370D01*
Y-33751D01*
X336208D01*
Y-33806D01*
X336154D01*
Y-33860D01*
X336100D01*
Y-33914D01*
X336046D01*
Y-33968D01*
X335992D01*
Y-34022D01*
X335938D01*
Y-34076D01*
X335883D01*
Y-34130D01*
X335829D01*
Y-34184D01*
X335775D01*
Y-34238D01*
X335721D01*
Y-34292D01*
X335667D01*
Y-34346D01*
X335613D01*
Y-34400D01*
X335559D01*
Y-34454D01*
X335505D01*
Y-34508D01*
X335451D01*
Y-34562D01*
X335397D01*
Y-34616D01*
X335343D01*
Y-34670D01*
X335289D01*
Y-34725D01*
X335235D01*
Y-34779D01*
X335181D01*
Y-34833D01*
X335127D01*
Y-34887D01*
X335073D01*
Y-34941D01*
X335018D01*
Y-34995D01*
X334964D01*
Y-35049D01*
X334910D01*
Y-35103D01*
X334856D01*
Y-35157D01*
X334802D01*
Y-35211D01*
X334748D01*
Y-35265D01*
X334694D01*
Y-35319D01*
X334640D01*
Y-35373D01*
X334586D01*
Y-35427D01*
Y-35481D01*
X334532D01*
Y-35535D01*
Y-35590D01*
Y-35644D01*
Y-35698D01*
X334478D01*
Y-35752D01*
Y-35806D01*
Y-35860D01*
Y-35914D01*
Y-35968D01*
Y-36022D01*
Y-36076D01*
Y-36130D01*
Y-36184D01*
Y-36238D01*
Y-36292D01*
Y-36346D01*
Y-36400D01*
Y-36454D01*
Y-36509D01*
Y-36563D01*
Y-36617D01*
Y-36671D01*
Y-36725D01*
Y-36779D01*
Y-36833D01*
Y-36887D01*
Y-36941D01*
Y-36995D01*
Y-37049D01*
Y-37103D01*
Y-37157D01*
Y-37211D01*
Y-37265D01*
Y-37319D01*
Y-37374D01*
Y-37428D01*
Y-37482D01*
Y-37536D01*
Y-37590D01*
Y-37644D01*
Y-37698D01*
Y-37752D01*
Y-37806D01*
Y-37860D01*
Y-37914D01*
Y-37968D01*
Y-38022D01*
Y-38076D01*
Y-38130D01*
Y-38184D01*
Y-38238D01*
Y-38293D01*
Y-38347D01*
Y-38401D01*
Y-38455D01*
Y-38509D01*
Y-38563D01*
Y-38617D01*
Y-38671D01*
Y-38725D01*
Y-38779D01*
Y-38833D01*
Y-38887D01*
Y-38941D01*
Y-38995D01*
Y-39050D01*
Y-39103D01*
Y-39158D01*
Y-39212D01*
Y-39266D01*
Y-39320D01*
Y-39374D01*
Y-39428D01*
Y-39482D01*
Y-39536D01*
Y-39590D01*
Y-39644D01*
Y-39698D01*
Y-39752D01*
Y-39806D01*
Y-39860D01*
Y-39915D01*
Y-39968D01*
Y-40023D01*
Y-40077D01*
Y-40131D01*
Y-40185D01*
Y-40239D01*
Y-40293D01*
Y-40347D01*
Y-40401D01*
Y-40455D01*
Y-40509D01*
Y-40563D01*
Y-40617D01*
Y-40671D01*
Y-40725D01*
Y-40780D01*
Y-40834D01*
Y-40888D01*
Y-40942D01*
Y-40996D01*
Y-41050D01*
Y-41104D01*
Y-41158D01*
Y-41212D01*
Y-41266D01*
Y-41320D01*
Y-41374D01*
Y-41428D01*
Y-41482D01*
Y-41536D01*
Y-41590D01*
Y-41644D01*
Y-41699D01*
Y-41753D01*
Y-41807D01*
Y-41861D01*
Y-41915D01*
Y-41969D01*
Y-42023D01*
Y-42077D01*
Y-42131D01*
Y-42185D01*
Y-42239D01*
Y-42293D01*
Y-42347D01*
Y-42401D01*
Y-42455D01*
Y-42509D01*
Y-42564D01*
Y-42618D01*
Y-42672D01*
Y-42726D01*
Y-42780D01*
Y-42834D01*
Y-42888D01*
Y-42942D01*
Y-42996D01*
Y-43050D01*
Y-43104D01*
Y-43158D01*
Y-43212D01*
Y-43266D01*
Y-43320D01*
Y-43374D01*
X334532D01*
Y-43429D01*
Y-43483D01*
Y-43537D01*
Y-43591D01*
X334586D01*
Y-43645D01*
Y-43699D01*
Y-43753D01*
X334640D01*
Y-43807D01*
X334694D01*
Y-43861D01*
X334748D01*
Y-43915D01*
X334802D01*
Y-43969D01*
X334856D01*
Y-44023D01*
X334910D01*
Y-44077D01*
X334964D01*
Y-44131D01*
X335018D01*
Y-44185D01*
X335073D01*
Y-44239D01*
X335127D01*
Y-44293D01*
X335181D01*
Y-44348D01*
X335235D01*
Y-44402D01*
X335289D01*
Y-44456D01*
X335343D01*
Y-44510D01*
X335397D01*
Y-44564D01*
X335451D01*
Y-44618D01*
X335505D01*
Y-44672D01*
X335559D01*
Y-44726D01*
X335613D01*
Y-44780D01*
X335667D01*
Y-44834D01*
X335721D01*
Y-44888D01*
X335775D01*
Y-44942D01*
X335829D01*
Y-44996D01*
X335883D01*
Y-45050D01*
X335938D01*
Y-45104D01*
X335992D01*
Y-45158D01*
X336046D01*
Y-45213D01*
X336100D01*
Y-45267D01*
X336154D01*
Y-45321D01*
X336262D01*
Y-45375D01*
X336478D01*
Y-45429D01*
X344209D01*
Y-45375D01*
X344263D01*
Y-45321D01*
X344317D01*
Y-45267D01*
X344371D01*
Y-45213D01*
Y-45158D01*
Y-45104D01*
Y-45050D01*
Y-44996D01*
Y-44942D01*
Y-44888D01*
Y-44834D01*
Y-44780D01*
Y-44726D01*
Y-44672D01*
Y-44618D01*
Y-44564D01*
Y-44510D01*
Y-44456D01*
Y-44402D01*
Y-44348D01*
Y-44293D01*
Y-44239D01*
Y-44185D01*
Y-44131D01*
Y-44077D01*
Y-44023D01*
Y-43969D01*
Y-43915D01*
Y-43861D01*
Y-43807D01*
Y-43753D01*
Y-43699D01*
Y-43645D01*
Y-43591D01*
Y-43537D01*
Y-43483D01*
Y-43429D01*
Y-43374D01*
Y-43320D01*
Y-43266D01*
Y-43212D01*
Y-43158D01*
Y-43104D01*
Y-43050D01*
Y-42996D01*
Y-42942D01*
Y-42888D01*
Y-42834D01*
Y-42780D01*
Y-42726D01*
Y-42672D01*
Y-42618D01*
Y-42564D01*
Y-42509D01*
Y-42455D01*
Y-42401D01*
Y-42347D01*
Y-42293D01*
Y-42239D01*
Y-42185D01*
Y-42131D01*
Y-42077D01*
Y-42023D01*
Y-41969D01*
Y-41915D01*
Y-41861D01*
Y-41807D01*
Y-41753D01*
Y-41699D01*
Y-41644D01*
Y-41590D01*
Y-41536D01*
Y-41482D01*
Y-41428D01*
Y-41374D01*
Y-41320D01*
Y-41266D01*
Y-41212D01*
Y-41158D01*
Y-41104D01*
Y-41050D01*
Y-40996D01*
Y-40942D01*
Y-40888D01*
Y-40834D01*
Y-40780D01*
Y-40725D01*
Y-40671D01*
Y-40617D01*
Y-40563D01*
Y-40509D01*
Y-40455D01*
Y-40401D01*
Y-40347D01*
Y-40293D01*
Y-40239D01*
Y-40185D01*
Y-40131D01*
Y-40077D01*
Y-40023D01*
Y-39968D01*
Y-39915D01*
Y-39860D01*
Y-39806D01*
Y-39752D01*
Y-39698D01*
Y-39644D01*
Y-39590D01*
Y-39536D01*
Y-39482D01*
Y-39428D01*
Y-39374D01*
Y-39320D01*
Y-39266D01*
Y-39212D01*
Y-39158D01*
Y-39103D01*
Y-39050D01*
Y-38995D01*
Y-38941D01*
Y-38887D01*
Y-38833D01*
Y-38779D01*
Y-38725D01*
Y-38671D01*
Y-38617D01*
Y-38563D01*
Y-38509D01*
Y-38455D01*
Y-38401D01*
Y-38347D01*
Y-38293D01*
Y-38238D01*
Y-38184D01*
Y-38130D01*
Y-38076D01*
Y-38022D01*
Y-37968D01*
Y-37914D01*
Y-37860D01*
Y-37806D01*
Y-37752D01*
Y-37698D01*
Y-37644D01*
Y-37590D01*
Y-37536D01*
Y-37482D01*
Y-37428D01*
Y-37374D01*
Y-37319D01*
Y-37265D01*
Y-37211D01*
Y-37157D01*
Y-37103D01*
Y-37049D01*
Y-36995D01*
Y-36941D01*
Y-36887D01*
Y-36833D01*
Y-36779D01*
Y-36725D01*
Y-36671D01*
Y-36617D01*
Y-36563D01*
Y-36509D01*
Y-36454D01*
Y-36400D01*
Y-36346D01*
Y-36292D01*
Y-36238D01*
Y-36184D01*
Y-36130D01*
Y-36076D01*
Y-36022D01*
Y-35968D01*
Y-35914D01*
Y-35860D01*
Y-35806D01*
Y-35752D01*
Y-35698D01*
Y-35644D01*
Y-35590D01*
Y-35535D01*
Y-35481D01*
Y-35427D01*
Y-35373D01*
Y-35319D01*
Y-35265D01*
Y-35211D01*
Y-35157D01*
Y-35103D01*
Y-35049D01*
Y-34995D01*
Y-34941D01*
Y-34887D01*
Y-34833D01*
Y-34779D01*
Y-34725D01*
Y-34670D01*
Y-34616D01*
Y-34562D01*
Y-34508D01*
Y-34454D01*
Y-34400D01*
Y-34346D01*
Y-34292D01*
Y-34238D01*
Y-34184D01*
Y-34130D01*
Y-34076D01*
Y-34022D01*
Y-33968D01*
Y-33914D01*
Y-33860D01*
X344317D01*
Y-33806D01*
X344263D01*
Y-33751D01*
X344209D01*
Y-33697D01*
X344101D01*
Y-33643D01*
D02*
G37*
G36*
X382863Y-33697D02*
X382215D01*
Y-33751D01*
Y-33806D01*
Y-33860D01*
Y-33914D01*
Y-33968D01*
Y-34022D01*
X382161D01*
Y-34076D01*
Y-34130D01*
Y-34184D01*
Y-34238D01*
Y-34292D01*
Y-34346D01*
Y-34400D01*
Y-34454D01*
Y-34508D01*
Y-34562D01*
Y-34616D01*
Y-34670D01*
Y-34725D01*
Y-34779D01*
Y-34833D01*
Y-34887D01*
X382107D01*
Y-34941D01*
Y-34995D01*
Y-35049D01*
Y-35103D01*
Y-35157D01*
Y-35211D01*
Y-35265D01*
Y-35319D01*
Y-35373D01*
Y-35427D01*
X382052D01*
Y-35481D01*
Y-35535D01*
Y-35590D01*
Y-35644D01*
Y-35698D01*
Y-35752D01*
Y-35806D01*
Y-35860D01*
X381998D01*
Y-35914D01*
Y-35968D01*
Y-36022D01*
Y-36076D01*
Y-36130D01*
Y-36184D01*
Y-36238D01*
X381944D01*
Y-36292D01*
Y-36346D01*
Y-36400D01*
Y-36454D01*
Y-36509D01*
Y-36563D01*
X381890D01*
Y-36617D01*
Y-36671D01*
Y-36725D01*
Y-36779D01*
Y-36833D01*
X381836D01*
Y-36887D01*
Y-36941D01*
Y-36995D01*
Y-37049D01*
Y-37103D01*
X381782D01*
Y-37157D01*
Y-37211D01*
Y-37265D01*
Y-37319D01*
Y-37374D01*
X381728D01*
Y-37428D01*
Y-37482D01*
Y-37536D01*
Y-37590D01*
Y-37644D01*
X381674D01*
Y-37698D01*
Y-37752D01*
Y-37806D01*
Y-37860D01*
X381620D01*
Y-37914D01*
Y-37968D01*
Y-38022D01*
Y-38076D01*
X381566D01*
Y-38130D01*
Y-38184D01*
Y-38238D01*
Y-38293D01*
X381512D01*
Y-38347D01*
Y-38401D01*
Y-38455D01*
Y-38509D01*
X381458D01*
Y-38563D01*
Y-38617D01*
Y-38671D01*
X381404D01*
Y-38725D01*
Y-38779D01*
Y-38833D01*
Y-38887D01*
X381350D01*
Y-38941D01*
Y-38995D01*
Y-39050D01*
X381296D01*
Y-39103D01*
Y-39158D01*
Y-39212D01*
X381242D01*
Y-39266D01*
Y-39320D01*
Y-39374D01*
X381188D01*
Y-39428D01*
Y-39482D01*
Y-39536D01*
X381133D01*
Y-39590D01*
Y-39644D01*
Y-39698D01*
X381079D01*
Y-39752D01*
Y-39806D01*
Y-39860D01*
X381025D01*
Y-39915D01*
Y-39968D01*
Y-40023D01*
X380971D01*
Y-40077D01*
Y-40131D01*
X380917D01*
Y-40185D01*
Y-40239D01*
Y-40293D01*
X380863D01*
Y-40347D01*
Y-40401D01*
Y-40455D01*
X380809D01*
Y-40509D01*
Y-40563D01*
X380755D01*
Y-40617D01*
Y-40671D01*
Y-40725D01*
X380701D01*
Y-40780D01*
Y-40834D01*
X380647D01*
Y-40888D01*
Y-40942D01*
X380593D01*
Y-40996D01*
Y-41050D01*
Y-41104D01*
X380539D01*
Y-41158D01*
Y-41212D01*
X380485D01*
Y-41266D01*
Y-41320D01*
X380431D01*
Y-41374D01*
Y-41428D01*
Y-41482D01*
X380377D01*
Y-41536D01*
Y-41590D01*
X380323D01*
Y-41644D01*
Y-41699D01*
X380268D01*
Y-41753D01*
Y-41807D01*
X380214D01*
Y-41861D01*
Y-41915D01*
X380160D01*
Y-41969D01*
Y-42023D01*
X380106D01*
Y-42077D01*
Y-42131D01*
X380052D01*
Y-42185D01*
Y-42239D01*
X379998D01*
Y-42293D01*
Y-42347D01*
X379944D01*
Y-42401D01*
Y-42455D01*
X379890D01*
Y-42509D01*
Y-42564D01*
X379836D01*
Y-42618D01*
Y-42672D01*
X379782D01*
Y-42726D01*
Y-42780D01*
X379728D01*
Y-42834D01*
X379674D01*
Y-42888D01*
Y-42942D01*
X379620D01*
Y-42996D01*
Y-43050D01*
X379566D01*
Y-43104D01*
Y-43158D01*
X379512D01*
Y-43212D01*
X379457D01*
Y-43266D01*
Y-43320D01*
X379403D01*
Y-43374D01*
Y-43429D01*
X379349D01*
Y-43483D01*
Y-43537D01*
X379295D01*
Y-43591D01*
X379241D01*
Y-43645D01*
Y-43699D01*
X379187D01*
Y-43753D01*
X379133D01*
Y-43807D01*
Y-43861D01*
X379079D01*
Y-43915D01*
Y-43969D01*
X379025D01*
Y-44023D01*
X378971D01*
Y-44077D01*
Y-44131D01*
X378917D01*
Y-44185D01*
X378863D01*
Y-44239D01*
Y-44293D01*
X378809D01*
Y-44348D01*
X378755D01*
Y-44402D01*
Y-44456D01*
X378701D01*
Y-44510D01*
X378647D01*
Y-44564D01*
Y-44618D01*
X378592D01*
Y-44672D01*
X378538D01*
Y-44726D01*
Y-44780D01*
X378484D01*
Y-44834D01*
X378430D01*
Y-44888D01*
X378376D01*
Y-44942D01*
Y-44996D01*
X378322D01*
Y-45050D01*
X378268D01*
Y-45104D01*
X378214D01*
Y-45158D01*
Y-45213D01*
X378160D01*
Y-45267D01*
X378106D01*
Y-45321D01*
X378052D01*
Y-45375D01*
Y-45429D01*
X377998D01*
Y-45483D01*
X377944D01*
Y-45537D01*
X377890D01*
Y-45591D01*
Y-45645D01*
X377836D01*
Y-45699D01*
X377782D01*
Y-45753D01*
X377728D01*
Y-45807D01*
X377674D01*
Y-45861D01*
Y-45915D01*
X377619D01*
Y-45969D01*
X377565D01*
Y-46023D01*
X377511D01*
Y-46077D01*
X377457D01*
Y-46132D01*
X377403D01*
Y-46186D01*
Y-46240D01*
X377349D01*
Y-46294D01*
X377295D01*
Y-46348D01*
X377241D01*
Y-46402D01*
X377187D01*
Y-46456D01*
X377133D01*
Y-46510D01*
X377079D01*
Y-46564D01*
X377025D01*
Y-46618D01*
Y-46672D01*
X376971D01*
Y-46726D01*
X376917D01*
Y-46780D01*
X376863D01*
Y-46834D01*
X376809D01*
Y-46889D01*
X376754D01*
Y-46942D01*
X376700D01*
Y-46997D01*
X376646D01*
Y-47051D01*
X376592D01*
Y-47105D01*
X376538D01*
Y-47159D01*
X376484D01*
Y-47213D01*
X376430D01*
Y-47267D01*
X376376D01*
Y-47321D01*
X376322D01*
Y-47375D01*
X376268D01*
Y-47429D01*
X376214D01*
Y-47483D01*
X376160D01*
Y-47537D01*
X376106D01*
Y-47591D01*
X376052D01*
Y-47645D01*
X375997D01*
Y-47699D01*
X375943D01*
Y-47754D01*
X375889D01*
Y-47807D01*
X375835D01*
Y-47862D01*
X375781D01*
Y-47916D01*
X375727D01*
Y-47970D01*
X375673D01*
Y-48024D01*
X375619D01*
Y-48078D01*
X375565D01*
Y-48132D01*
X375457D01*
Y-48186D01*
X375403D01*
Y-48240D01*
X375349D01*
Y-48294D01*
X375295D01*
Y-48348D01*
X375241D01*
Y-48402D01*
X375187D01*
Y-48456D01*
X375132D01*
Y-48510D01*
X375024D01*
Y-48564D01*
X374970D01*
Y-48619D01*
X374916D01*
Y-48673D01*
X374862D01*
Y-48727D01*
X374808D01*
Y-48781D01*
X374700D01*
Y-48835D01*
X374646D01*
Y-48889D01*
X374592D01*
Y-48943D01*
X374538D01*
Y-48997D01*
X374430D01*
Y-49051D01*
X374376D01*
Y-49105D01*
X374322D01*
Y-49159D01*
X374214D01*
Y-49213D01*
X374159D01*
Y-49267D01*
X374105D01*
Y-49321D01*
X373997D01*
Y-49375D01*
X373943D01*
Y-49429D01*
X373889D01*
Y-49483D01*
X373781D01*
Y-49538D01*
X373727D01*
Y-49592D01*
X373673D01*
Y-49646D01*
X373565D01*
Y-49700D01*
X373511D01*
Y-49754D01*
X373403D01*
Y-49808D01*
X373348D01*
Y-49862D01*
X373240D01*
Y-49916D01*
X373186D01*
Y-49970D01*
X373078D01*
Y-50024D01*
X373024D01*
Y-50078D01*
X372916D01*
Y-50132D01*
X372862D01*
Y-50186D01*
X372754D01*
Y-50240D01*
X372646D01*
Y-50294D01*
X372592D01*
Y-50348D01*
X372483D01*
Y-50402D01*
X372429D01*
Y-50457D01*
X372321D01*
Y-50511D01*
X372213D01*
Y-50565D01*
X372159D01*
Y-50619D01*
X372051D01*
Y-50673D01*
X371943D01*
Y-50727D01*
X371835D01*
Y-50781D01*
X371727D01*
Y-50835D01*
X371673D01*
Y-50889D01*
X371565D01*
Y-50943D01*
X371456D01*
Y-50997D01*
X371348D01*
Y-51051D01*
X371240D01*
Y-51105D01*
X371132D01*
Y-51159D01*
X371024D01*
Y-51213D01*
X370916D01*
Y-51267D01*
X370808D01*
Y-51322D01*
X370700D01*
Y-51376D01*
X370591D01*
Y-51430D01*
X370483D01*
Y-51484D01*
X370375D01*
Y-51538D01*
X370213D01*
Y-51592D01*
X370105D01*
Y-51646D01*
X369997D01*
Y-51700D01*
X369888D01*
Y-51754D01*
X369726D01*
Y-51808D01*
X369618D01*
Y-51862D01*
X369456D01*
Y-51916D01*
X369348D01*
Y-51970D01*
X369186D01*
Y-52024D01*
X369078D01*
Y-52078D01*
X368915D01*
Y-52132D01*
X368753D01*
Y-52187D01*
X368591D01*
Y-52241D01*
X368429D01*
Y-52295D01*
X368267D01*
Y-52349D01*
X368105D01*
Y-52403D01*
X367942D01*
Y-52457D01*
X367780D01*
Y-52511D01*
X367564D01*
Y-52565D01*
X367402D01*
Y-52619D01*
X367185D01*
Y-52673D01*
X366969D01*
Y-52727D01*
X366753D01*
Y-52781D01*
X366537D01*
Y-52835D01*
X366320D01*
Y-52889D01*
X366050D01*
Y-52943D01*
X365780D01*
Y-52997D01*
X365456D01*
Y-53052D01*
X365131D01*
Y-53106D01*
X364753D01*
Y-53160D01*
X364320D01*
Y-53214D01*
X363834D01*
Y-53268D01*
X363023D01*
Y-53322D01*
X360914D01*
Y-53268D01*
X360806D01*
Y-53322D01*
X360752D01*
Y-53268D01*
X360157D01*
Y-53214D01*
X359509D01*
Y-53160D01*
X359184D01*
Y-53106D01*
X358806D01*
Y-53052D01*
X358481D01*
Y-52997D01*
X358157D01*
Y-52943D01*
X357887D01*
Y-52889D01*
X357670D01*
Y-52835D01*
X357400D01*
Y-52781D01*
X357184D01*
Y-52727D01*
X356968D01*
Y-52673D01*
X356751D01*
Y-52619D01*
X356535D01*
Y-52565D01*
X356373D01*
Y-52511D01*
X356157D01*
Y-52457D01*
X355995D01*
Y-52403D01*
X355832D01*
Y-52349D01*
X355670D01*
Y-52295D01*
X355508D01*
Y-52241D01*
X355346D01*
Y-52187D01*
X355184D01*
Y-52132D01*
X355022D01*
Y-52078D01*
X354913D01*
Y-52024D01*
X354751D01*
Y-51970D01*
X354589D01*
Y-51916D01*
X354481D01*
Y-51862D01*
X354319D01*
Y-51808D01*
X354211D01*
Y-51754D01*
X354102D01*
Y-51700D01*
X353940D01*
Y-51646D01*
X353832D01*
Y-51592D01*
X353670D01*
Y-51538D01*
X353562D01*
Y-51484D01*
X353454D01*
Y-51430D01*
X353346D01*
Y-51376D01*
X353237D01*
Y-51322D01*
X353129D01*
Y-51267D01*
X353021D01*
Y-51213D01*
X352913D01*
Y-51159D01*
X352805D01*
Y-51105D01*
X352697D01*
Y-51051D01*
X352589D01*
Y-50997D01*
X352481D01*
Y-50943D01*
X352372D01*
Y-50889D01*
X352264D01*
Y-50835D01*
X352210D01*
Y-50781D01*
X352102D01*
Y-50727D01*
X351994D01*
Y-50673D01*
X351886D01*
Y-50619D01*
X351832D01*
Y-50565D01*
X351724D01*
Y-50511D01*
X351616D01*
Y-50457D01*
X351561D01*
Y-50402D01*
X351453D01*
Y-50348D01*
X351345D01*
Y-50294D01*
X351291D01*
Y-50240D01*
X351183D01*
Y-50186D01*
X351075D01*
Y-50132D01*
X351021D01*
Y-50078D01*
X350913D01*
Y-50024D01*
X350859D01*
Y-49970D01*
X350751D01*
Y-49916D01*
X350696D01*
Y-49862D01*
X350588D01*
Y-49808D01*
X350534D01*
Y-49754D01*
X350426D01*
Y-49700D01*
X350372D01*
Y-49646D01*
X350318D01*
Y-49592D01*
X350210D01*
Y-49538D01*
X350156D01*
Y-49483D01*
X350048D01*
Y-49429D01*
X349994D01*
Y-49375D01*
X349940D01*
Y-49321D01*
X349832D01*
Y-49267D01*
X349778D01*
Y-49213D01*
X349723D01*
Y-49159D01*
X349615D01*
Y-49105D01*
X349561D01*
Y-49051D01*
X349507D01*
Y-48997D01*
X349453D01*
Y-48943D01*
X349345D01*
Y-48889D01*
X349291D01*
Y-48835D01*
X349237D01*
Y-48781D01*
X349183D01*
Y-48727D01*
X349075D01*
Y-48673D01*
X349021D01*
Y-48619D01*
X348967D01*
Y-48564D01*
X348913D01*
Y-48510D01*
X348858D01*
Y-48456D01*
X348750D01*
Y-48402D01*
X348696D01*
Y-48348D01*
X348642D01*
Y-48294D01*
X348588D01*
Y-48240D01*
X348534D01*
Y-48186D01*
X348480D01*
Y-48132D01*
X348426D01*
Y-48078D01*
X348318D01*
Y-48024D01*
X348264D01*
Y-47970D01*
X348210D01*
Y-47916D01*
X348156D01*
Y-47862D01*
X348101D01*
Y-47807D01*
X348047D01*
Y-47754D01*
X347993D01*
Y-47699D01*
X347939D01*
Y-47645D01*
X347885D01*
Y-47591D01*
X347831D01*
Y-47537D01*
X347777D01*
Y-47483D01*
X347723D01*
Y-47429D01*
X347669D01*
Y-47375D01*
X347615D01*
Y-47321D01*
X347561D01*
Y-47267D01*
X347507D01*
Y-47213D01*
X347453D01*
Y-47159D01*
X347399D01*
Y-47105D01*
X347345D01*
Y-47051D01*
X347291D01*
Y-46997D01*
X347236D01*
Y-46942D01*
X347182D01*
Y-46889D01*
X347128D01*
Y-46834D01*
X347074D01*
Y-46780D01*
X347020D01*
Y-46726D01*
X346966D01*
Y-46672D01*
Y-46618D01*
X346912D01*
Y-46564D01*
X346858D01*
Y-46510D01*
X345993D01*
Y-46564D01*
X346047D01*
Y-46618D01*
Y-46672D01*
X346101D01*
Y-46726D01*
X346155D01*
Y-46780D01*
X346209D01*
Y-46834D01*
X346263D01*
Y-46889D01*
X346318D01*
Y-46942D01*
X346372D01*
Y-46997D01*
X346426D01*
Y-47051D01*
Y-47105D01*
X346480D01*
Y-47159D01*
X346534D01*
Y-47213D01*
X346588D01*
Y-47267D01*
X346642D01*
Y-47321D01*
X346696D01*
Y-47375D01*
X346750D01*
Y-47429D01*
X346804D01*
Y-47483D01*
X346858D01*
Y-47537D01*
X346912D01*
Y-47591D01*
X346966D01*
Y-47645D01*
X347020D01*
Y-47699D01*
X347074D01*
Y-47754D01*
X347128D01*
Y-47807D01*
X347182D01*
Y-47862D01*
X347236D01*
Y-47916D01*
X347291D01*
Y-47970D01*
X347345D01*
Y-48024D01*
X347399D01*
Y-48078D01*
X347453D01*
Y-48132D01*
X347507D01*
Y-48186D01*
X347561D01*
Y-48240D01*
X347615D01*
Y-48294D01*
X347669D01*
Y-48348D01*
X347723D01*
Y-48402D01*
X347777D01*
Y-48456D01*
X347831D01*
Y-48510D01*
X347885D01*
Y-48564D01*
X347939D01*
Y-48619D01*
X348047D01*
Y-48673D01*
X348101D01*
Y-48727D01*
X348156D01*
Y-48781D01*
X348210D01*
Y-48835D01*
X348264D01*
Y-48889D01*
X348318D01*
Y-48943D01*
X348372D01*
Y-48997D01*
X348480D01*
Y-49051D01*
X348534D01*
Y-49105D01*
X348588D01*
Y-49159D01*
X348642D01*
Y-49213D01*
X348696D01*
Y-49267D01*
X348804D01*
Y-49321D01*
X348858D01*
Y-49375D01*
X348913D01*
Y-49429D01*
X348967D01*
Y-49483D01*
X349075D01*
Y-49538D01*
X349129D01*
Y-49592D01*
X349183D01*
Y-49646D01*
X349237D01*
Y-49700D01*
X349345D01*
Y-49754D01*
X349399D01*
Y-49808D01*
X349453D01*
Y-49862D01*
X349561D01*
Y-49916D01*
X349615D01*
Y-49970D01*
X349669D01*
Y-50024D01*
X349778D01*
Y-50078D01*
X349832D01*
Y-50132D01*
X349940D01*
Y-50186D01*
X349994D01*
Y-50240D01*
X350102D01*
Y-50294D01*
X350156D01*
Y-50348D01*
X350210D01*
Y-50402D01*
X350318D01*
Y-50457D01*
X350372D01*
Y-50511D01*
X350480D01*
Y-50565D01*
X350534D01*
Y-50619D01*
X350642D01*
Y-50673D01*
X350751D01*
Y-50727D01*
X350805D01*
Y-50781D01*
X350913D01*
Y-50835D01*
X350967D01*
Y-50889D01*
X351075D01*
Y-50943D01*
X351183D01*
Y-50997D01*
X351237D01*
Y-51051D01*
X351345D01*
Y-51105D01*
X351453D01*
Y-51159D01*
X351507D01*
Y-51213D01*
X351616D01*
Y-51267D01*
X351724D01*
Y-51322D01*
X351832D01*
Y-51376D01*
X351886D01*
Y-51430D01*
X351994D01*
Y-51484D01*
X352102D01*
Y-51538D01*
X352210D01*
Y-51592D01*
X352318D01*
Y-51646D01*
X352427D01*
Y-51700D01*
X352535D01*
Y-51754D01*
X352643D01*
Y-51808D01*
X352751D01*
Y-51862D01*
X352859D01*
Y-51916D01*
X352967D01*
Y-51970D01*
X353075D01*
Y-52024D01*
X353183D01*
Y-52078D01*
X353292D01*
Y-52132D01*
X353400D01*
Y-52187D01*
X353562D01*
Y-52241D01*
X353670D01*
Y-52295D01*
X353778D01*
Y-52349D01*
X353940D01*
Y-52403D01*
X354048D01*
Y-52457D01*
X354211D01*
Y-52511D01*
X354319D01*
Y-52565D01*
X354481D01*
Y-52619D01*
X354589D01*
Y-52673D01*
X354751D01*
Y-52727D01*
X354913D01*
Y-52781D01*
X355076D01*
Y-52835D01*
X355238D01*
Y-52889D01*
X355400D01*
Y-52943D01*
X355562D01*
Y-52997D01*
X355724D01*
Y-53052D01*
X355887D01*
Y-53106D01*
X356049D01*
Y-53160D01*
X356265D01*
Y-53214D01*
X356427D01*
Y-53268D01*
X356643D01*
Y-53322D01*
X356860D01*
Y-53376D01*
X357076D01*
Y-53430D01*
X357346D01*
Y-53484D01*
X357562D01*
Y-53538D01*
X357779D01*
Y-53592D01*
X358103D01*
Y-53646D01*
X358373D01*
Y-53700D01*
X358698D01*
Y-53754D01*
X359076D01*
Y-53808D01*
X359509D01*
Y-53863D01*
X359995D01*
Y-53917D01*
X360698D01*
Y-53971D01*
X363293D01*
Y-53917D01*
X363942D01*
Y-53863D01*
X364482D01*
Y-53808D01*
X364861D01*
Y-53754D01*
X365239D01*
Y-53700D01*
X365564D01*
Y-53646D01*
X365888D01*
Y-53592D01*
X366158D01*
Y-53538D01*
X366374D01*
Y-53484D01*
X366645D01*
Y-53430D01*
X366861D01*
Y-53376D01*
X367077D01*
Y-53322D01*
X367294D01*
Y-53268D01*
X367510D01*
Y-53214D01*
X367672D01*
Y-53160D01*
X367888D01*
Y-53106D01*
X368050D01*
Y-53052D01*
X368213D01*
Y-52997D01*
X368429D01*
Y-52943D01*
X368591D01*
Y-52889D01*
X368753D01*
Y-52835D01*
X368861D01*
Y-52781D01*
X369023D01*
Y-52727D01*
X369186D01*
Y-52673D01*
X369348D01*
Y-52619D01*
X369456D01*
Y-52565D01*
X369618D01*
Y-52511D01*
X369726D01*
Y-52457D01*
X369888D01*
Y-52403D01*
X369997D01*
Y-52349D01*
X370159D01*
Y-52295D01*
X370267D01*
Y-52241D01*
X370375D01*
Y-52187D01*
X370537D01*
Y-52132D01*
X370645D01*
Y-52078D01*
X370754D01*
Y-52024D01*
X370862D01*
Y-51970D01*
X370970D01*
Y-51916D01*
X371078D01*
Y-51862D01*
X371186D01*
Y-51808D01*
X371294D01*
Y-51754D01*
X371402D01*
Y-51700D01*
X371510D01*
Y-51646D01*
X371619D01*
Y-51592D01*
X371727D01*
Y-51538D01*
X371835D01*
Y-51484D01*
X371943D01*
Y-51430D01*
X372051D01*
Y-51376D01*
X372159D01*
Y-51322D01*
X372213D01*
Y-51267D01*
X372321D01*
Y-51213D01*
X372429D01*
Y-51159D01*
X372538D01*
Y-51105D01*
X372592D01*
Y-51051D01*
X372700D01*
Y-50997D01*
X372808D01*
Y-50943D01*
X372862D01*
Y-50889D01*
X372970D01*
Y-50835D01*
X373024D01*
Y-50781D01*
X373132D01*
Y-50727D01*
X373240D01*
Y-50673D01*
X373294D01*
Y-50619D01*
X373403D01*
Y-50565D01*
X373457D01*
Y-50511D01*
X373565D01*
Y-50457D01*
X373619D01*
Y-50402D01*
X373727D01*
Y-50348D01*
X373781D01*
Y-50294D01*
X373889D01*
Y-50240D01*
X373943D01*
Y-50186D01*
X373997D01*
Y-50132D01*
X374105D01*
Y-50078D01*
X374159D01*
Y-50024D01*
X374268D01*
Y-49970D01*
X374322D01*
Y-49916D01*
X374376D01*
Y-49862D01*
X374484D01*
Y-49808D01*
X374538D01*
Y-49754D01*
X374592D01*
Y-49700D01*
X374700D01*
Y-49646D01*
X374754D01*
Y-49592D01*
X374808D01*
Y-49538D01*
X374916D01*
Y-49483D01*
X374970D01*
Y-49429D01*
X375024D01*
Y-49375D01*
X375079D01*
Y-49321D01*
X375187D01*
Y-49267D01*
X375241D01*
Y-49213D01*
X375295D01*
Y-49159D01*
X375349D01*
Y-49105D01*
X375403D01*
Y-49051D01*
X375511D01*
Y-48997D01*
X375565D01*
Y-48943D01*
X375619D01*
Y-48889D01*
X375673D01*
Y-48835D01*
X375727D01*
Y-48781D01*
X375781D01*
Y-48727D01*
X375835D01*
Y-48673D01*
X375943D01*
Y-48619D01*
X375997D01*
Y-48564D01*
X376052D01*
Y-48510D01*
X376106D01*
Y-48456D01*
X376160D01*
Y-48402D01*
X376214D01*
Y-48348D01*
X376268D01*
Y-48294D01*
X376322D01*
Y-48240D01*
X376376D01*
Y-48186D01*
X376430D01*
Y-48132D01*
X376484D01*
Y-48078D01*
X376538D01*
Y-48024D01*
X376592D01*
Y-47970D01*
X376646D01*
Y-47916D01*
X376700D01*
Y-47862D01*
X376754D01*
Y-47807D01*
X376809D01*
Y-47754D01*
X376863D01*
Y-47699D01*
X376917D01*
Y-47645D01*
X376971D01*
Y-47591D01*
X377025D01*
Y-47537D01*
X377079D01*
Y-47483D01*
X377133D01*
Y-47429D01*
X377187D01*
Y-47375D01*
X377241D01*
Y-47321D01*
X377295D01*
Y-47267D01*
X377349D01*
Y-47213D01*
X377403D01*
Y-47159D01*
X377457D01*
Y-47105D01*
X377511D01*
Y-47051D01*
X377565D01*
Y-46997D01*
Y-46942D01*
X377619D01*
Y-46889D01*
X377674D01*
Y-46834D01*
X377728D01*
Y-46780D01*
X377782D01*
Y-46726D01*
X377836D01*
Y-46672D01*
X377890D01*
Y-46618D01*
X377944D01*
Y-46564D01*
Y-46510D01*
X377998D01*
Y-46456D01*
X378052D01*
Y-46402D01*
X378106D01*
Y-46348D01*
X378160D01*
Y-46294D01*
Y-46240D01*
X378214D01*
Y-46186D01*
X378268D01*
Y-46132D01*
X378322D01*
Y-46077D01*
X378376D01*
Y-46023D01*
Y-45969D01*
X378430D01*
Y-45915D01*
X378484D01*
Y-45861D01*
X378538D01*
Y-45807D01*
X378592D01*
Y-45753D01*
Y-45699D01*
X378647D01*
Y-45645D01*
X378701D01*
Y-45591D01*
X378755D01*
Y-45537D01*
Y-45483D01*
X378809D01*
Y-45429D01*
X378863D01*
Y-45375D01*
X378917D01*
Y-45321D01*
Y-45267D01*
X378971D01*
Y-45213D01*
X379025D01*
Y-45158D01*
Y-45104D01*
X379079D01*
Y-45050D01*
X379133D01*
Y-44996D01*
X379187D01*
Y-44942D01*
Y-44888D01*
X379241D01*
Y-44834D01*
X379295D01*
Y-44780D01*
Y-44726D01*
X379349D01*
Y-44672D01*
X379403D01*
Y-44618D01*
Y-44564D01*
X379457D01*
Y-44510D01*
X379512D01*
Y-44456D01*
Y-44402D01*
X379566D01*
Y-44348D01*
X379620D01*
Y-44293D01*
Y-44239D01*
X379674D01*
Y-44185D01*
Y-44131D01*
X379728D01*
Y-44077D01*
X379782D01*
Y-44023D01*
Y-43969D01*
X379836D01*
Y-43915D01*
X379890D01*
Y-43861D01*
Y-43807D01*
X379944D01*
Y-43753D01*
Y-43699D01*
X379998D01*
Y-43645D01*
Y-43591D01*
X380052D01*
Y-43537D01*
X380106D01*
Y-43483D01*
Y-43429D01*
X380160D01*
Y-43374D01*
Y-43320D01*
X380214D01*
Y-43266D01*
Y-43212D01*
X380268D01*
Y-43158D01*
Y-43104D01*
X380323D01*
Y-43050D01*
X380377D01*
Y-42996D01*
Y-42942D01*
X380431D01*
Y-42888D01*
Y-42834D01*
X380485D01*
Y-42780D01*
Y-42726D01*
X380539D01*
Y-42672D01*
Y-42618D01*
X380593D01*
Y-42564D01*
Y-42509D01*
X380647D01*
Y-42455D01*
Y-42401D01*
X380701D01*
Y-42347D01*
Y-42293D01*
X380755D01*
Y-42239D01*
Y-42185D01*
X380809D01*
Y-42131D01*
Y-42077D01*
X380863D01*
Y-42023D01*
Y-41969D01*
X380917D01*
Y-41915D01*
Y-41861D01*
X380971D01*
Y-41807D01*
Y-41753D01*
X381025D01*
Y-41699D01*
Y-41644D01*
X381079D01*
Y-41590D01*
Y-41536D01*
Y-41482D01*
X381133D01*
Y-41428D01*
Y-41374D01*
X381188D01*
Y-41320D01*
Y-41266D01*
X381242D01*
Y-41212D01*
Y-41158D01*
Y-41104D01*
X381296D01*
Y-41050D01*
Y-40996D01*
X381350D01*
Y-40942D01*
Y-40888D01*
Y-40834D01*
X381404D01*
Y-40780D01*
Y-40725D01*
X381458D01*
Y-40671D01*
Y-40617D01*
Y-40563D01*
X381512D01*
Y-40509D01*
Y-40455D01*
X381566D01*
Y-40401D01*
Y-40347D01*
Y-40293D01*
X381620D01*
Y-40239D01*
Y-40185D01*
Y-40131D01*
X381674D01*
Y-40077D01*
Y-40023D01*
Y-39968D01*
X381728D01*
Y-39915D01*
Y-39860D01*
Y-39806D01*
X381782D01*
Y-39752D01*
Y-39698D01*
Y-39644D01*
X381836D01*
Y-39590D01*
Y-39536D01*
Y-39482D01*
X381890D01*
Y-39428D01*
Y-39374D01*
Y-39320D01*
X381944D01*
Y-39266D01*
Y-39212D01*
Y-39158D01*
X381998D01*
Y-39103D01*
Y-39050D01*
Y-38995D01*
X382052D01*
Y-38941D01*
Y-38887D01*
Y-38833D01*
Y-38779D01*
X382107D01*
Y-38725D01*
Y-38671D01*
Y-38617D01*
X382161D01*
Y-38563D01*
Y-38509D01*
Y-38455D01*
Y-38401D01*
X382215D01*
Y-38347D01*
Y-38293D01*
Y-38238D01*
Y-38184D01*
X382269D01*
Y-38130D01*
Y-38076D01*
Y-38022D01*
Y-37968D01*
X382323D01*
Y-37914D01*
Y-37860D01*
Y-37806D01*
Y-37752D01*
X382377D01*
Y-37698D01*
Y-37644D01*
Y-37590D01*
Y-37536D01*
Y-37482D01*
X382431D01*
Y-37428D01*
Y-37374D01*
Y-37319D01*
Y-37265D01*
Y-37211D01*
X382485D01*
Y-37157D01*
Y-37103D01*
Y-37049D01*
Y-36995D01*
Y-36941D01*
X382539D01*
Y-36887D01*
Y-36833D01*
Y-36779D01*
Y-36725D01*
Y-36671D01*
X382593D01*
Y-36617D01*
Y-36563D01*
Y-36509D01*
Y-36454D01*
Y-36400D01*
Y-36346D01*
X382647D01*
Y-36292D01*
Y-36238D01*
Y-36184D01*
Y-36130D01*
Y-36076D01*
Y-36022D01*
Y-35968D01*
X382701D01*
Y-35914D01*
Y-35860D01*
Y-35806D01*
Y-35752D01*
Y-35698D01*
Y-35644D01*
Y-35590D01*
Y-35535D01*
X382755D01*
Y-35481D01*
Y-35427D01*
Y-35373D01*
Y-35319D01*
Y-35265D01*
Y-35211D01*
Y-35157D01*
Y-35103D01*
Y-35049D01*
Y-34995D01*
X382809D01*
Y-34941D01*
X382755D01*
Y-34887D01*
X382809D01*
Y-34833D01*
Y-34779D01*
Y-34725D01*
Y-34670D01*
Y-34616D01*
Y-34562D01*
Y-34508D01*
Y-34454D01*
Y-34400D01*
Y-34346D01*
Y-34292D01*
X382863D01*
Y-34238D01*
Y-34184D01*
Y-34130D01*
Y-34076D01*
Y-34022D01*
Y-33968D01*
Y-33914D01*
Y-33860D01*
Y-33806D01*
Y-33751D01*
Y-33697D01*
D02*
G37*
%LPD*%
G36*
X353021Y-36454D02*
Y-36509D01*
Y-36563D01*
Y-36617D01*
Y-36671D01*
Y-36725D01*
Y-36779D01*
Y-36833D01*
Y-36887D01*
Y-36941D01*
Y-36995D01*
Y-37049D01*
Y-37103D01*
Y-37157D01*
Y-37211D01*
Y-37265D01*
Y-37319D01*
Y-37374D01*
Y-37428D01*
Y-37482D01*
Y-37536D01*
Y-37590D01*
Y-37644D01*
Y-37698D01*
Y-37752D01*
Y-37806D01*
Y-37860D01*
Y-37914D01*
Y-37968D01*
Y-38022D01*
Y-38076D01*
Y-38130D01*
Y-38184D01*
Y-38238D01*
Y-38293D01*
Y-38347D01*
Y-38401D01*
Y-38455D01*
Y-38509D01*
Y-38563D01*
Y-38617D01*
Y-38671D01*
Y-38725D01*
Y-38779D01*
Y-38833D01*
Y-38887D01*
Y-38941D01*
Y-38995D01*
Y-39050D01*
Y-39103D01*
Y-39158D01*
Y-39212D01*
Y-39266D01*
X348967D01*
Y-39212D01*
Y-39158D01*
Y-39103D01*
Y-39050D01*
Y-38995D01*
Y-38941D01*
Y-38887D01*
Y-38833D01*
Y-38779D01*
Y-38725D01*
Y-38671D01*
Y-38617D01*
Y-38563D01*
Y-38509D01*
Y-38455D01*
Y-38401D01*
Y-38347D01*
Y-38293D01*
Y-38238D01*
Y-38184D01*
Y-38130D01*
Y-38076D01*
Y-38022D01*
Y-37968D01*
Y-37914D01*
Y-37860D01*
Y-37806D01*
Y-37752D01*
Y-37698D01*
Y-37644D01*
Y-37590D01*
Y-37536D01*
Y-37482D01*
Y-37428D01*
Y-37374D01*
Y-37319D01*
Y-37265D01*
Y-37211D01*
Y-37157D01*
Y-37103D01*
Y-37049D01*
Y-36995D01*
Y-36941D01*
Y-36887D01*
Y-36833D01*
Y-36779D01*
Y-36725D01*
Y-36671D01*
Y-36617D01*
Y-36563D01*
Y-36509D01*
Y-36454D01*
Y-36400D01*
X353021D01*
Y-36454D01*
D02*
G37*
G36*
X341344Y-36563D02*
X341398D01*
Y-36617D01*
Y-36671D01*
Y-36725D01*
Y-36779D01*
Y-36833D01*
Y-36887D01*
Y-36941D01*
Y-36995D01*
Y-37049D01*
Y-37103D01*
Y-37157D01*
Y-37211D01*
Y-37265D01*
Y-37319D01*
Y-37374D01*
Y-37428D01*
Y-37482D01*
Y-37536D01*
Y-37590D01*
Y-37644D01*
Y-37698D01*
Y-37752D01*
Y-37806D01*
Y-37860D01*
Y-37914D01*
Y-37968D01*
Y-38022D01*
Y-38076D01*
Y-38130D01*
Y-38184D01*
Y-38238D01*
Y-38293D01*
Y-38347D01*
Y-38401D01*
Y-38455D01*
Y-38509D01*
Y-38563D01*
Y-38617D01*
Y-38671D01*
Y-38725D01*
Y-38779D01*
Y-38833D01*
Y-38887D01*
Y-38941D01*
Y-38995D01*
Y-39050D01*
Y-39103D01*
Y-39158D01*
Y-39212D01*
Y-39266D01*
Y-39320D01*
Y-39374D01*
Y-39428D01*
Y-39482D01*
Y-39536D01*
Y-39590D01*
Y-39644D01*
Y-39698D01*
Y-39752D01*
Y-39806D01*
Y-39860D01*
Y-39915D01*
Y-39968D01*
Y-40023D01*
Y-40077D01*
Y-40131D01*
Y-40185D01*
Y-40239D01*
Y-40293D01*
Y-40347D01*
Y-40401D01*
Y-40455D01*
Y-40509D01*
Y-40563D01*
Y-40617D01*
Y-40671D01*
Y-40725D01*
Y-40780D01*
Y-40834D01*
Y-40888D01*
Y-40942D01*
Y-40996D01*
Y-41050D01*
Y-41104D01*
Y-41158D01*
Y-41212D01*
Y-41266D01*
Y-41320D01*
Y-41374D01*
Y-41428D01*
Y-41482D01*
Y-41536D01*
Y-41590D01*
Y-41644D01*
Y-41699D01*
Y-41753D01*
Y-41807D01*
Y-41861D01*
Y-41915D01*
Y-41969D01*
Y-42023D01*
Y-42077D01*
Y-42131D01*
Y-42185D01*
Y-42239D01*
Y-42293D01*
Y-42347D01*
Y-42401D01*
Y-42455D01*
Y-42509D01*
Y-42564D01*
X337451D01*
Y-42509D01*
Y-42455D01*
Y-42401D01*
Y-42347D01*
Y-42293D01*
Y-42239D01*
Y-42185D01*
Y-42131D01*
Y-42077D01*
Y-42023D01*
Y-41969D01*
Y-41915D01*
Y-41861D01*
Y-41807D01*
Y-41753D01*
Y-41699D01*
Y-41644D01*
Y-41590D01*
Y-41536D01*
Y-41482D01*
Y-41428D01*
Y-41374D01*
Y-41320D01*
Y-41266D01*
Y-41212D01*
Y-41158D01*
Y-41104D01*
Y-41050D01*
Y-40996D01*
Y-40942D01*
Y-40888D01*
Y-40834D01*
Y-40780D01*
Y-40725D01*
Y-40671D01*
Y-40617D01*
Y-40563D01*
Y-40509D01*
Y-40455D01*
Y-40401D01*
Y-40347D01*
Y-40293D01*
Y-40239D01*
Y-40185D01*
Y-40131D01*
Y-40077D01*
Y-40023D01*
Y-39968D01*
Y-39915D01*
Y-39860D01*
Y-39806D01*
Y-39752D01*
Y-39698D01*
Y-39644D01*
Y-39590D01*
Y-39536D01*
Y-39482D01*
Y-39428D01*
Y-39374D01*
Y-39320D01*
Y-39266D01*
Y-39212D01*
Y-39158D01*
Y-39103D01*
Y-39050D01*
Y-38995D01*
Y-38941D01*
Y-38887D01*
Y-38833D01*
Y-38779D01*
Y-38725D01*
Y-38671D01*
Y-38617D01*
Y-38563D01*
Y-38509D01*
Y-38455D01*
Y-38401D01*
Y-38347D01*
Y-38293D01*
Y-38238D01*
Y-38184D01*
Y-38130D01*
Y-38076D01*
Y-38022D01*
Y-37968D01*
Y-37914D01*
Y-37860D01*
Y-37806D01*
Y-37752D01*
Y-37698D01*
Y-37644D01*
Y-37590D01*
Y-37536D01*
Y-37482D01*
Y-37428D01*
Y-37374D01*
Y-37319D01*
Y-37265D01*
Y-37211D01*
Y-37157D01*
Y-37103D01*
Y-37049D01*
Y-36995D01*
Y-36941D01*
Y-36887D01*
Y-36833D01*
Y-36779D01*
Y-36725D01*
Y-36671D01*
Y-36617D01*
Y-36563D01*
X337560D01*
Y-36509D01*
X337614D01*
Y-36563D01*
X337722D01*
Y-36509D01*
X337776D01*
Y-36563D01*
X341290D01*
Y-36509D01*
X341344D01*
Y-36563D01*
D02*
G37*
D72*
X281102Y-401427D02*
D03*
X159055D02*
D03*
X155118D02*
D03*
X186614D02*
D03*
X182677D02*
D03*
X241732D02*
D03*
X273228D02*
D03*
X269291D02*
D03*
X257480D02*
D03*
X237795D02*
D03*
X253543D02*
D03*
X222047D02*
D03*
X218110D02*
D03*
X210236D02*
D03*
X206299D02*
D03*
X190551D02*
D03*
X166929D02*
D03*
X170866D02*
D03*
X174803D02*
D03*
X178740D02*
D03*
X229921D02*
D03*
X214173D02*
D03*
X202362D02*
D03*
X249606D02*
D03*
X265354D02*
D03*
X245669D02*
D03*
X277165D02*
D03*
X261417D02*
D03*
X233858D02*
D03*
X225984D02*
D03*
X162992D02*
D03*
D73*
X151181Y-399477D02*
D03*
D173*
X273441Y-382293D02*
D03*
Y-378907D02*
D03*
X206441D02*
D03*
Y-382293D02*
D03*
X210441D02*
D03*
Y-378907D02*
D03*
X218341D02*
D03*
Y-382293D02*
D03*
X222641D02*
D03*
Y-378907D02*
D03*
X237941Y-382293D02*
D03*
Y-378907D02*
D03*
X241941Y-382293D02*
D03*
Y-378907D02*
D03*
X253441Y-382293D02*
D03*
Y-378907D02*
D03*
X256941D02*
D03*
Y-382293D02*
D03*
X269441D02*
D03*
Y-378907D02*
D03*
M02*
